FILE_TYPE = MACRO_DRAWING;
SET COLOR_WIRE YELLOW;
SET COLOR_PROP ORANGE;
SET COLOR_DOT WHITE;
SET COLOR_ARC YELLOW;
SET COLOR_BODY GREEN;
SET COLOR_NOTE PURPLE;
SET PROP_DISPLAY VALUE;
SET PAGE_NUMBER P112;
FORCEADD OFFPAGE..2
R 2
(-4175 350);
FORCEPROP 2 LAST $XR0 112 
J 0
(-4460 350);
DISPLAY 0.638298 (-4460 350);
PAINT MONO (-4460 350);
FORCEPROP 2 LAST CDS_LIB standard
J 0
(-4175 350);
PAINT MONO (-4175 350);
DISPLAY INVISIBLE (-4175 350);
FORCEPROP 1 LAST OFFPAGE TRUE
J 2
(-4500 225);
DISPLAY 0.872340 (-4500 225);
DISPLAY INVISIBLE (-4500 225);
FORCEPROP 1 LAST COMMENT_BODY TRUE
J 2
(-4130 255);
DISPLAY 0.872340 (-4130 255);
PAINT GREEN (-4130 255);
DISPLAY INVISIBLE (-4130 255);
FORCEPROP 2 LAST PATH I1
J 0
(-4125 425);
DISPLAY 1.021277 (-4125 425);
DISPLAY INVISIBLE (-4125 425);
FORCEADD OFFPAGE..1
(-4175 1950);
FORCEPROP 2 LAST $XR1 113 
J 0
(-4516 1950);
DISPLAY 0.638298 (-4516 1950);
PAINT MONO (-4516 1950);
FORCEPROP 2 LAST $XR0 58 
J 0
(-4396 1950);
DISPLAY 0.638298 (-4396 1950);
PAINT MONO (-4396 1950);
FORCEPROP 2 LAST CDS_LIB standard
J 0
(-4175 1950);
PAINT MONO (-4175 1950);
DISPLAY INVISIBLE (-4175 1950);
FORCEPROP 1 LAST OFFPAGE TRUE
J 0
(-3850 1825);
DISPLAY 0.872340 (-3850 1825);
DISPLAY INVISIBLE (-3850 1825);
FORCEPROP 1 LAST COMMENT_BODY TRUE
J 0
(-4050 1850);
DISPLAY 0.872340 (-4050 1850);
PAINT GREEN (-4050 1850);
DISPLAY INVISIBLE (-4050 1850);
FORCEPROP 2 LAST PATH I10
J 0
(-4125 2025);
DISPLAY 1.021277 (-4125 2025);
DISPLAY INVISIBLE (-4125 2025);
FORCEADD TAP..1
(-1600 3350);
FORCEPROP 3 LASTPIN (-1650 3350) SIG_NAME M_H_CPU1_SA_DQ<12>
J 0
(-1640 3360);
DISPLAY 0.659574 (-1640 3360);
PAINT MONO (-1640 3360);
DISPLAY INVISIBLE (-1640 3360);
FORCEPROP 1 LASTPIN (-1650 3350) BN 12
J 0
(-1662 3358);
DISPLAY 0.680851 (-1662 3358);
PAINT GREEN (-1662 3358);
FORCEPROP 2 LAST CDS_LIB standard
J 0
(-1600 3350);
PAINT MONO (-1600 3350);
DISPLAY INVISIBLE (-1600 3350);
FORCEPROP 1 LAST BODY_TYPE PLUMBING
J 0
(-1600 3400);
DISPLAY 0.872340 (-1600 3400);
PAINT GREEN (-1600 3400);
DISPLAY INVISIBLE (-1600 3400);
FORCEPROP 1 LAST HDL_TAP TRUE
J 0
(-1275 3225);
DISPLAY 0.872340 (-1275 3225);
DISPLAY INVISIBLE (-1275 3225);
FORCEPROP 1 LAST PATH I100
J 0
(-1602 3350);
DISPLAY 0.872340 (-1602 3350);
PAINT GREEN (-1602 3350);
DISPLAY INVISIBLE (-1602 3350);
FORCEADD OFFPAGE..3
(-775 2675);
FORCEPROP 2 LAST $XR1 113 
J 0
(-471 2675);
DISPLAY 0.638298 (-471 2675);
PAINT MONO (-471 2675);
FORCEPROP 2 LAST $XR0 58 
J 0
(-561 2675);
DISPLAY 0.638298 (-561 2675);
PAINT MONO (-561 2675);
FORCEPROP 2 LAST CDS_LIB standard
J 2
(-775 2675);
DISPLAY INVISIBLE (-775 2675);
FORCEPROP 1 LAST OFFPAGE TRUE
J 0
(-450 2550);
DISPLAY 0.872340 (-450 2550);
DISPLAY INVISIBLE (-450 2550);
FORCEPROP 1 LAST COMMENT_BODY TRUE
J 0
(-825 2575);
DISPLAY 0.872340 (-825 2575);
PAINT GREEN (-825 2575);
DISPLAY INVISIBLE (-825 2575);
FORCEPROP 2 LAST PATH I101
J 0
(-575 2750);
DISPLAY 1.021277 (-575 2750);
DISPLAY INVISIBLE (-575 2750);
FORCEADD TAP..1
(-1600 3450);
FORCEPROP 3 LASTPIN (-1650 3450) SIG_NAME M_H_CPU1_SA_DQ<14>
J 0
(-1640 3460);
DISPLAY 0.659574 (-1640 3460);
PAINT MONO (-1640 3460);
DISPLAY INVISIBLE (-1640 3460);
FORCEPROP 1 LASTPIN (-1650 3450) BN 14
J 0
(-1662 3458);
DISPLAY 0.680851 (-1662 3458);
PAINT GREEN (-1662 3458);
FORCEPROP 2 LAST CDS_LIB standard
J 0
(-1600 3450);
PAINT MONO (-1600 3450);
DISPLAY INVISIBLE (-1600 3450);
FORCEPROP 1 LAST BODY_TYPE PLUMBING
J 0
(-1600 3500);
DISPLAY 0.872340 (-1600 3500);
PAINT GREEN (-1600 3500);
DISPLAY INVISIBLE (-1600 3500);
FORCEPROP 1 LAST HDL_TAP TRUE
J 0
(-1275 3325);
DISPLAY 0.872340 (-1275 3325);
DISPLAY INVISIBLE (-1275 3325);
FORCEPROP 1 LAST PATH I102
J 0
(-1602 3450);
DISPLAY 0.872340 (-1602 3450);
PAINT GREEN (-1602 3450);
DISPLAY INVISIBLE (-1602 3450);
FORCEADD TAP..1
(-1600 3400);
FORCEPROP 3 LASTPIN (-1650 3400) SIG_NAME M_H_CPU1_SA_DQ<13>
J 0
(-1640 3410);
DISPLAY 0.659574 (-1640 3410);
PAINT MONO (-1640 3410);
DISPLAY INVISIBLE (-1640 3410);
FORCEPROP 1 LASTPIN (-1650 3400) BN 13
J 0
(-1662 3408);
DISPLAY 0.680851 (-1662 3408);
PAINT GREEN (-1662 3408);
FORCEPROP 2 LAST CDS_LIB standard
J 0
(-1600 3400);
PAINT MONO (-1600 3400);
DISPLAY INVISIBLE (-1600 3400);
FORCEPROP 1 LAST BODY_TYPE PLUMBING
J 0
(-1600 3450);
DISPLAY 0.872340 (-1600 3450);
PAINT GREEN (-1600 3450);
DISPLAY INVISIBLE (-1600 3450);
FORCEPROP 1 LAST HDL_TAP TRUE
J 0
(-1275 3275);
DISPLAY 0.872340 (-1275 3275);
DISPLAY INVISIBLE (-1275 3275);
FORCEPROP 1 LAST PATH I103
J 0
(-1602 3400);
DISPLAY 0.872340 (-1602 3400);
PAINT GREEN (-1602 3400);
DISPLAY INVISIBLE (-1602 3400);
FORCEADD TAP..1
(-1600 3500);
FORCEPROP 3 LASTPIN (-1650 3500) SIG_NAME M_H_CPU1_SA_DQ<15>
J 0
(-1640 3510);
DISPLAY 0.659574 (-1640 3510);
PAINT MONO (-1640 3510);
DISPLAY INVISIBLE (-1640 3510);
FORCEPROP 1 LASTPIN (-1650 3500) BN 15
J 0
(-1662 3508);
DISPLAY 0.680851 (-1662 3508);
PAINT GREEN (-1662 3508);
FORCEPROP 2 LAST CDS_LIB standard
J 0
(-1600 3500);
PAINT MONO (-1600 3500);
DISPLAY INVISIBLE (-1600 3500);
FORCEPROP 1 LAST BODY_TYPE PLUMBING
J 0
(-1600 3550);
DISPLAY 0.872340 (-1600 3550);
PAINT GREEN (-1600 3550);
DISPLAY INVISIBLE (-1600 3550);
FORCEPROP 1 LAST HDL_TAP TRUE
J 0
(-1275 3375);
DISPLAY 0.872340 (-1275 3375);
DISPLAY INVISIBLE (-1275 3375);
FORCEPROP 1 LAST PATH I104
J 0
(-1602 3500);
DISPLAY 0.872340 (-1602 3500);
PAINT GREEN (-1602 3500);
DISPLAY INVISIBLE (-1602 3500);
FORCEADD TAP..1
(-1600 3550);
FORCEPROP 3 LASTPIN (-1650 3550) SIG_NAME M_H_CPU1_SA_DQ<16>
J 0
(-1640 3560);
DISPLAY 0.659574 (-1640 3560);
PAINT MONO (-1640 3560);
DISPLAY INVISIBLE (-1640 3560);
FORCEPROP 1 LASTPIN (-1650 3550) BN 16
J 0
(-1662 3558);
DISPLAY 0.680851 (-1662 3558);
PAINT GREEN (-1662 3558);
FORCEPROP 2 LAST CDS_LIB standard
J 0
(-1600 3550);
PAINT MONO (-1600 3550);
DISPLAY INVISIBLE (-1600 3550);
FORCEPROP 1 LAST BODY_TYPE PLUMBING
J 0
(-1600 3600);
DISPLAY 0.872340 (-1600 3600);
PAINT GREEN (-1600 3600);
DISPLAY INVISIBLE (-1600 3600);
FORCEPROP 1 LAST HDL_TAP TRUE
J 0
(-1275 3425);
DISPLAY 0.872340 (-1275 3425);
DISPLAY INVISIBLE (-1275 3425);
FORCEPROP 1 LAST PATH I105
J 0
(-1602 3550);
DISPLAY 0.872340 (-1602 3550);
PAINT GREEN (-1602 3550);
DISPLAY INVISIBLE (-1602 3550);
FORCEADD TAP..1
(-1600 3600);
FORCEPROP 3 LASTPIN (-1650 3600) SIG_NAME M_H_CPU1_SA_DQ<17>
J 0
(-1640 3610);
DISPLAY 0.659574 (-1640 3610);
PAINT MONO (-1640 3610);
DISPLAY INVISIBLE (-1640 3610);
FORCEPROP 1 LASTPIN (-1650 3600) BN 17
J 0
(-1662 3608);
DISPLAY 0.680851 (-1662 3608);
PAINT GREEN (-1662 3608);
FORCEPROP 2 LAST CDS_LIB standard
J 0
(-1600 3600);
PAINT MONO (-1600 3600);
DISPLAY INVISIBLE (-1600 3600);
FORCEPROP 1 LAST BODY_TYPE PLUMBING
J 0
(-1600 3650);
DISPLAY 0.872340 (-1600 3650);
PAINT GREEN (-1600 3650);
DISPLAY INVISIBLE (-1600 3650);
FORCEPROP 1 LAST HDL_TAP TRUE
J 0
(-1275 3475);
DISPLAY 0.872340 (-1275 3475);
DISPLAY INVISIBLE (-1275 3475);
FORCEPROP 1 LAST PATH I106
J 0
(-1602 3600);
DISPLAY 0.872340 (-1602 3600);
PAINT GREEN (-1602 3600);
DISPLAY INVISIBLE (-1602 3600);
FORCEADD TAP..1
(-1600 3650);
FORCEPROP 3 LASTPIN (-1650 3650) SIG_NAME M_H_CPU1_SA_DQ<18>
J 0
(-1640 3660);
DISPLAY 0.659574 (-1640 3660);
PAINT MONO (-1640 3660);
DISPLAY INVISIBLE (-1640 3660);
FORCEPROP 1 LASTPIN (-1650 3650) BN 18
J 0
(-1662 3658);
DISPLAY 0.680851 (-1662 3658);
PAINT GREEN (-1662 3658);
FORCEPROP 2 LAST CDS_LIB standard
J 0
(-1600 3650);
PAINT MONO (-1600 3650);
DISPLAY INVISIBLE (-1600 3650);
FORCEPROP 1 LAST BODY_TYPE PLUMBING
J 0
(-1600 3700);
DISPLAY 0.872340 (-1600 3700);
PAINT GREEN (-1600 3700);
DISPLAY INVISIBLE (-1600 3700);
FORCEPROP 1 LAST HDL_TAP TRUE
J 0
(-1275 3525);
DISPLAY 0.872340 (-1275 3525);
DISPLAY INVISIBLE (-1275 3525);
FORCEPROP 1 LAST PATH I107
J 0
(-1602 3650);
DISPLAY 0.872340 (-1602 3650);
PAINT GREEN (-1602 3650);
DISPLAY INVISIBLE (-1602 3650);
FORCEADD TAP..1
(-1600 3700);
FORCEPROP 3 LASTPIN (-1650 3700) SIG_NAME M_H_CPU1_SA_DQ<19>
J 0
(-1640 3710);
DISPLAY 0.659574 (-1640 3710);
PAINT MONO (-1640 3710);
DISPLAY INVISIBLE (-1640 3710);
FORCEPROP 1 LASTPIN (-1650 3700) BN 19
J 0
(-1662 3708);
DISPLAY 0.680851 (-1662 3708);
PAINT GREEN (-1662 3708);
FORCEPROP 2 LAST CDS_LIB standard
J 0
(-1600 3700);
PAINT MONO (-1600 3700);
DISPLAY INVISIBLE (-1600 3700);
FORCEPROP 1 LAST BODY_TYPE PLUMBING
J 0
(-1600 3750);
DISPLAY 0.872340 (-1600 3750);
PAINT GREEN (-1600 3750);
DISPLAY INVISIBLE (-1600 3750);
FORCEPROP 1 LAST HDL_TAP TRUE
J 0
(-1275 3575);
DISPLAY 0.872340 (-1275 3575);
DISPLAY INVISIBLE (-1275 3575);
FORCEPROP 1 LAST PATH I108
J 0
(-1602 3700);
DISPLAY 0.872340 (-1602 3700);
PAINT GREEN (-1602 3700);
DISPLAY INVISIBLE (-1602 3700);
FORCEADD TAP..1
(-1600 3750);
FORCEPROP 3 LASTPIN (-1650 3750) SIG_NAME M_H_CPU1_SA_DQ<20>
J 0
(-1640 3760);
DISPLAY 0.659574 (-1640 3760);
PAINT MONO (-1640 3760);
DISPLAY INVISIBLE (-1640 3760);
FORCEPROP 1 LASTPIN (-1650 3750) BN 20
J 0
(-1662 3758);
DISPLAY 0.680851 (-1662 3758);
PAINT GREEN (-1662 3758);
FORCEPROP 2 LAST CDS_LIB standard
J 0
(-1600 3750);
PAINT MONO (-1600 3750);
DISPLAY INVISIBLE (-1600 3750);
FORCEPROP 1 LAST BODY_TYPE PLUMBING
J 0
(-1600 3800);
DISPLAY 0.872340 (-1600 3800);
PAINT GREEN (-1600 3800);
DISPLAY INVISIBLE (-1600 3800);
FORCEPROP 1 LAST HDL_TAP TRUE
J 0
(-1275 3625);
DISPLAY 0.872340 (-1275 3625);
DISPLAY INVISIBLE (-1275 3625);
FORCEPROP 1 LAST PATH I109
J 0
(-1602 3750);
DISPLAY 0.872340 (-1602 3750);
PAINT GREEN (-1602 3750);
DISPLAY INVISIBLE (-1602 3750);
FORCEADD OFFPAGE..1
(-4175 2075);
FORCEPROP 2 LAST $XR3 113 
J 0
(-4547 2039);
DISPLAY 0.638298 (-4547 2039);
PAINT MONO (-4547 2039);
FORCEPROP 2 LAST $XR2 111 
J 0
(-4427 2039);
DISPLAY 0.638298 (-4427 2039);
PAINT MONO (-4427 2039);
FORCEPROP 2 LAST $XR1 110 
J 0
(-4547 2075);
DISPLAY 0.638298 (-4547 2075);
PAINT MONO (-4547 2075);
FORCEPROP 2 LAST $XR0 130 
J 0
(-4427 2075);
DISPLAY 0.638298 (-4427 2075);
PAINT MONO (-4427 2075);
FORCEPROP 2 LAST CDS_LIB standard
J 0
(-4175 2075);
PAINT MONO (-4175 2075);
DISPLAY INVISIBLE (-4175 2075);
FORCEPROP 1 LAST OFFPAGE TRUE
J 0
(-3850 1950);
DISPLAY 0.872340 (-3850 1950);
DISPLAY INVISIBLE (-3850 1950);
FORCEPROP 1 LAST COMMENT_BODY TRUE
J 0
(-4050 1975);
DISPLAY 0.872340 (-4050 1975);
PAINT GREEN (-4050 1975);
DISPLAY INVISIBLE (-4050 1975);
FORCEPROP 2 LAST PATH I11
J 0
(-4125 2150);
DISPLAY 1.021277 (-4125 2150);
DISPLAY INVISIBLE (-4125 2150);
FORCEADD TAP..1
(-1600 3800);
FORCEPROP 3 LASTPIN (-1650 3800) SIG_NAME M_H_CPU1_SA_DQ<21>
J 0
(-1640 3810);
DISPLAY 0.659574 (-1640 3810);
PAINT MONO (-1640 3810);
DISPLAY INVISIBLE (-1640 3810);
FORCEPROP 1 LASTPIN (-1650 3800) BN 21
J 0
(-1662 3808);
DISPLAY 0.680851 (-1662 3808);
PAINT GREEN (-1662 3808);
FORCEPROP 2 LAST CDS_LIB standard
J 0
(-1600 3800);
PAINT MONO (-1600 3800);
DISPLAY INVISIBLE (-1600 3800);
FORCEPROP 1 LAST BODY_TYPE PLUMBING
J 0
(-1600 3850);
DISPLAY 0.872340 (-1600 3850);
PAINT GREEN (-1600 3850);
DISPLAY INVISIBLE (-1600 3850);
FORCEPROP 1 LAST HDL_TAP TRUE
J 0
(-1275 3675);
DISPLAY 0.872340 (-1275 3675);
DISPLAY INVISIBLE (-1275 3675);
FORCEPROP 1 LAST PATH I110
J 0
(-1602 3800);
DISPLAY 0.872340 (-1602 3800);
PAINT GREEN (-1602 3800);
DISPLAY INVISIBLE (-1602 3800);
FORCEADD TAP..1
(-1600 3850);
FORCEPROP 3 LASTPIN (-1650 3850) SIG_NAME M_H_CPU1_SA_DQ<22>
J 0
(-1640 3860);
DISPLAY 0.659574 (-1640 3860);
PAINT MONO (-1640 3860);
DISPLAY INVISIBLE (-1640 3860);
FORCEPROP 1 LASTPIN (-1650 3850) BN 22
J 0
(-1662 3858);
DISPLAY 0.680851 (-1662 3858);
PAINT GREEN (-1662 3858);
FORCEPROP 2 LAST CDS_LIB standard
J 0
(-1600 3850);
DISPLAY INVISIBLE (-1600 3850);
FORCEPROP 1 LAST BODY_TYPE PLUMBING
J 0
(-1600 3900);
DISPLAY 0.872340 (-1600 3900);
PAINT GREEN (-1600 3900);
DISPLAY INVISIBLE (-1600 3900);
FORCEPROP 1 LAST HDL_TAP TRUE
J 0
(-1275 3725);
DISPLAY 0.872340 (-1275 3725);
DISPLAY INVISIBLE (-1275 3725);
FORCEPROP 1 LAST PATH I111
J 0
(-1602 3850);
DISPLAY 0.872340 (-1602 3850);
PAINT GREEN (-1602 3850);
DISPLAY INVISIBLE (-1602 3850);
FORCEADD TAP..1
(-1600 3900);
FORCEPROP 3 LASTPIN (-1650 3900) SIG_NAME M_H_CPU1_SA_DQ<23>
J 0
(-1640 3910);
DISPLAY 0.659574 (-1640 3910);
PAINT MONO (-1640 3910);
DISPLAY INVISIBLE (-1640 3910);
FORCEPROP 1 LASTPIN (-1650 3900) BN 23
J 0
(-1662 3908);
DISPLAY 0.680851 (-1662 3908);
PAINT GREEN (-1662 3908);
FORCEPROP 2 LAST CDS_LIB standard
J 0
(-1600 3900);
DISPLAY INVISIBLE (-1600 3900);
FORCEPROP 1 LAST BODY_TYPE PLUMBING
J 0
(-1600 3950);
DISPLAY 0.872340 (-1600 3950);
PAINT GREEN (-1600 3950);
DISPLAY INVISIBLE (-1600 3950);
FORCEPROP 1 LAST HDL_TAP TRUE
J 0
(-1275 3775);
DISPLAY 0.872340 (-1275 3775);
DISPLAY INVISIBLE (-1275 3775);
FORCEPROP 1 LAST PATH I112
J 0
(-1602 3900);
DISPLAY 0.872340 (-1602 3900);
PAINT GREEN (-1602 3900);
DISPLAY INVISIBLE (-1602 3900);
FORCEADD TAP..1
(-1600 3950);
FORCEPROP 3 LASTPIN (-1650 3950) SIG_NAME M_H_CPU1_SA_DQ<24>
J 0
(-1640 3960);
DISPLAY 0.659574 (-1640 3960);
PAINT MONO (-1640 3960);
DISPLAY INVISIBLE (-1640 3960);
FORCEPROP 1 LASTPIN (-1650 3950) BN 24
J 0
(-1662 3958);
DISPLAY 0.680851 (-1662 3958);
PAINT GREEN (-1662 3958);
FORCEPROP 2 LAST CDS_LIB standard
J 0
(-1600 3950);
DISPLAY INVISIBLE (-1600 3950);
FORCEPROP 1 LAST BODY_TYPE PLUMBING
J 0
(-1600 4000);
DISPLAY 0.872340 (-1600 4000);
PAINT GREEN (-1600 4000);
DISPLAY INVISIBLE (-1600 4000);
FORCEPROP 1 LAST HDL_TAP TRUE
J 0
(-1275 3825);
DISPLAY 0.872340 (-1275 3825);
DISPLAY INVISIBLE (-1275 3825);
FORCEPROP 1 LAST PATH I113
J 0
(-1602 3950);
DISPLAY 0.872340 (-1602 3950);
PAINT GREEN (-1602 3950);
DISPLAY INVISIBLE (-1602 3950);
FORCEADD TAP..1
(-1600 4000);
FORCEPROP 3 LASTPIN (-1650 4000) SIG_NAME M_H_CPU1_SA_DQ<25>
J 0
(-1640 4010);
DISPLAY 0.659574 (-1640 4010);
PAINT MONO (-1640 4010);
DISPLAY INVISIBLE (-1640 4010);
FORCEPROP 1 LASTPIN (-1650 4000) BN 25
J 0
(-1662 4008);
DISPLAY 0.680851 (-1662 4008);
PAINT GREEN (-1662 4008);
FORCEPROP 2 LAST CDS_LIB standard
J 0
(-1600 4000);
DISPLAY INVISIBLE (-1600 4000);
FORCEPROP 1 LAST BODY_TYPE PLUMBING
J 0
(-1600 4050);
DISPLAY 0.872340 (-1600 4050);
PAINT GREEN (-1600 4050);
DISPLAY INVISIBLE (-1600 4050);
FORCEPROP 1 LAST HDL_TAP TRUE
J 0
(-1275 3875);
DISPLAY 0.872340 (-1275 3875);
DISPLAY INVISIBLE (-1275 3875);
FORCEPROP 1 LAST PATH I114
J 0
(-1602 4000);
DISPLAY 0.872340 (-1602 4000);
PAINT GREEN (-1602 4000);
DISPLAY INVISIBLE (-1602 4000);
FORCEADD TAP..1
(-1600 4100);
FORCEPROP 3 LASTPIN (-1650 4100) SIG_NAME M_H_CPU1_SA_DQ<27>
J 0
(-1640 4110);
DISPLAY 0.659574 (-1640 4110);
PAINT MONO (-1640 4110);
DISPLAY INVISIBLE (-1640 4110);
FORCEPROP 1 LASTPIN (-1650 4100) BN 27
J 0
(-1662 4108);
DISPLAY 0.680851 (-1662 4108);
PAINT GREEN (-1662 4108);
FORCEPROP 2 LAST CDS_LIB standard
J 0
(-1600 4100);
DISPLAY INVISIBLE (-1600 4100);
FORCEPROP 1 LAST BODY_TYPE PLUMBING
J 0
(-1600 4150);
DISPLAY 0.872340 (-1600 4150);
PAINT GREEN (-1600 4150);
DISPLAY INVISIBLE (-1600 4150);
FORCEPROP 1 LAST HDL_TAP TRUE
J 0
(-1275 3975);
DISPLAY 0.872340 (-1275 3975);
DISPLAY INVISIBLE (-1275 3975);
FORCEPROP 1 LAST PATH I115
J 0
(-1602 4100);
DISPLAY 0.872340 (-1602 4100);
PAINT GREEN (-1602 4100);
DISPLAY INVISIBLE (-1602 4100);
FORCEADD TAP..1
(-1600 4050);
FORCEPROP 3 LASTPIN (-1650 4050) SIG_NAME M_H_CPU1_SA_DQ<26>
J 0
(-1640 4060);
DISPLAY 0.659574 (-1640 4060);
PAINT MONO (-1640 4060);
DISPLAY INVISIBLE (-1640 4060);
FORCEPROP 1 LASTPIN (-1650 4050) BN 26
J 0
(-1662 4058);
DISPLAY 0.680851 (-1662 4058);
PAINT GREEN (-1662 4058);
FORCEPROP 2 LAST CDS_LIB standard
J 0
(-1600 4050);
DISPLAY INVISIBLE (-1600 4050);
FORCEPROP 1 LAST BODY_TYPE PLUMBING
J 0
(-1600 4100);
DISPLAY 0.872340 (-1600 4100);
PAINT GREEN (-1600 4100);
DISPLAY INVISIBLE (-1600 4100);
FORCEPROP 1 LAST HDL_TAP TRUE
J 0
(-1275 3925);
DISPLAY 0.872340 (-1275 3925);
DISPLAY INVISIBLE (-1275 3925);
FORCEPROP 1 LAST PATH I116
J 0
(-1602 4050);
DISPLAY 0.872340 (-1602 4050);
PAINT GREEN (-1602 4050);
DISPLAY INVISIBLE (-1602 4050);
FORCEADD TAP..1
(-1600 4150);
FORCEPROP 3 LASTPIN (-1650 4150) SIG_NAME M_H_CPU1_SA_DQ<28>
J 0
(-1640 4160);
DISPLAY 0.659574 (-1640 4160);
PAINT MONO (-1640 4160);
DISPLAY INVISIBLE (-1640 4160);
FORCEPROP 1 LASTPIN (-1650 4150) BN 28
J 0
(-1662 4158);
DISPLAY 0.680851 (-1662 4158);
PAINT GREEN (-1662 4158);
FORCEPROP 2 LAST CDS_LIB standard
J 0
(-1600 4150);
DISPLAY INVISIBLE (-1600 4150);
FORCEPROP 1 LAST BODY_TYPE PLUMBING
J 0
(-1600 4200);
DISPLAY 0.872340 (-1600 4200);
PAINT GREEN (-1600 4200);
DISPLAY INVISIBLE (-1600 4200);
FORCEPROP 1 LAST HDL_TAP TRUE
J 0
(-1275 4025);
DISPLAY 0.872340 (-1275 4025);
DISPLAY INVISIBLE (-1275 4025);
FORCEPROP 1 LAST PATH I117
J 0
(-1602 4150);
DISPLAY 0.872340 (-1602 4150);
PAINT GREEN (-1602 4150);
DISPLAY INVISIBLE (-1602 4150);
FORCEADD TAP..1
(-1600 4300);
FORCEPROP 3 LASTPIN (-1650 4300) SIG_NAME M_H_CPU1_SA_DQ<31>
J 0
(-1640 4310);
DISPLAY 0.659574 (-1640 4310);
PAINT MONO (-1640 4310);
DISPLAY INVISIBLE (-1640 4310);
FORCEPROP 1 LASTPIN (-1650 4300) BN 31
J 0
(-1662 4308);
DISPLAY 0.680851 (-1662 4308);
PAINT GREEN (-1662 4308);
FORCEPROP 2 LAST CDS_LIB standard
J 0
(-1600 4300);
DISPLAY INVISIBLE (-1600 4300);
FORCEPROP 1 LAST BODY_TYPE PLUMBING
J 0
(-1600 4350);
DISPLAY 0.872340 (-1600 4350);
PAINT GREEN (-1600 4350);
DISPLAY INVISIBLE (-1600 4350);
FORCEPROP 1 LAST HDL_TAP TRUE
J 0
(-1275 4175);
DISPLAY 0.872340 (-1275 4175);
DISPLAY INVISIBLE (-1275 4175);
FORCEPROP 1 LAST PATH I118
J 0
(-1602 4300);
DISPLAY 0.872340 (-1602 4300);
PAINT GREEN (-1602 4300);
DISPLAY INVISIBLE (-1602 4300);
FORCEADD TAP..1
(-1600 4200);
FORCEPROP 3 LASTPIN (-1650 4200) SIG_NAME M_H_CPU1_SA_DQ<29>
J 0
(-1640 4210);
DISPLAY 0.659574 (-1640 4210);
PAINT MONO (-1640 4210);
DISPLAY INVISIBLE (-1640 4210);
FORCEPROP 1 LASTPIN (-1650 4200) BN 29
J 0
(-1662 4208);
DISPLAY 0.680851 (-1662 4208);
PAINT GREEN (-1662 4208);
FORCEPROP 2 LAST CDS_LIB standard
J 0
(-1600 4200);
DISPLAY INVISIBLE (-1600 4200);
FORCEPROP 1 LAST BODY_TYPE PLUMBING
J 0
(-1600 4250);
DISPLAY 0.872340 (-1600 4250);
PAINT GREEN (-1600 4250);
DISPLAY INVISIBLE (-1600 4250);
FORCEPROP 1 LAST HDL_TAP TRUE
J 0
(-1275 4075);
DISPLAY 0.872340 (-1275 4075);
DISPLAY INVISIBLE (-1275 4075);
FORCEPROP 1 LAST PATH I119
J 0
(-1602 4200);
DISPLAY 0.872340 (-1602 4200);
PAINT GREEN (-1602 4200);
DISPLAY INVISIBLE (-1602 4200);
FORCEADD VCC_CORE..1
(-4075 2175);
FORCEPROP 3 LASTPIN (-4075 2125) SIG_NAME P3V3_AUX\g
J 0
(-4065 2135);
DISPLAY 0.659574 (-4065 2135);
PAINT MONO (-4065 2135);
DISPLAY INVISIBLE (-4065 2135);
FORCEPROP 1 LAST HDL_POWER P3V3_AUX
J 1
(-4075 2225);
DISPLAY 1.148936 (-4075 2225);
PAINT GREEN (-4075 2225);
FORCEPROP 2 LAST CDS_LIB logical_power
J 0
(-4075 2175);
PAINT MONO (-4075 2175);
DISPLAY INVISIBLE (-4075 2175);
FORCEPROP 1 LAST PATH I12
J 0
(-4025 2200);
DISPLAY 0.872340 (-4025 2200);
PAINT AQUA (-4025 2200);
DISPLAY INVISIBLE (-4025 2200);
FORCEADD TAP..1
(-1600 4250);
FORCEPROP 3 LASTPIN (-1650 4250) SIG_NAME M_H_CPU1_SA_DQ<30>
J 0
(-1640 4260);
DISPLAY 0.659574 (-1640 4260);
PAINT MONO (-1640 4260);
DISPLAY INVISIBLE (-1640 4260);
FORCEPROP 1 LASTPIN (-1650 4250) BN 30
J 0
(-1662 4258);
DISPLAY 0.680851 (-1662 4258);
PAINT GREEN (-1662 4258);
FORCEPROP 2 LAST CDS_LIB standard
J 0
(-1600 4250);
DISPLAY INVISIBLE (-1600 4250);
FORCEPROP 1 LAST BODY_TYPE PLUMBING
J 0
(-1600 4300);
DISPLAY 0.872340 (-1600 4300);
PAINT GREEN (-1600 4300);
DISPLAY INVISIBLE (-1600 4300);
FORCEPROP 1 LAST HDL_TAP TRUE
J 0
(-1275 4125);
DISPLAY 0.872340 (-1275 4125);
DISPLAY INVISIBLE (-1275 4125);
FORCEPROP 1 LAST PATH I120
J 0
(-1602 4250);
DISPLAY 0.872340 (-1602 4250);
PAINT GREEN (-1602 4250);
DISPLAY INVISIBLE (-1602 4250);
FORCEADD OFFPAGE..3
(-775 4325);
FORCEPROP 2 LAST $XR1 113 
J 0
(-471 4325);
DISPLAY 0.638298 (-471 4325);
PAINT MONO (-471 4325);
FORCEPROP 2 LAST $XR0 58 
J 0
(-561 4325);
DISPLAY 0.638298 (-561 4325);
PAINT MONO (-561 4325);
FORCEPROP 2 LAST CDS_LIB standard
J 2
(-775 4325);
DISPLAY INVISIBLE (-775 4325);
FORCEPROP 1 LAST OFFPAGE TRUE
J 0
(-450 4200);
DISPLAY 0.872340 (-450 4200);
DISPLAY INVISIBLE (-450 4200);
FORCEPROP 1 LAST COMMENT_BODY TRUE
J 0
(-825 4225);
DISPLAY 0.872340 (-825 4225);
PAINT GREEN (-825 4225);
DISPLAY INVISIBLE (-825 4225);
FORCEPROP 2 LAST PATH I121
J 0
(-575 4400);
DISPLAY 1.021277 (-575 4400);
DISPLAY INVISIBLE (-575 4400);
FORCEADD UNIVERSAL_GND..1
(125 50);
FORCEPROP 3 LASTPIN (125 100) SIG_NAME GND\g
J 0
(135 110);
DISPLAY 0.659574 (135 110);
PAINT MONO (135 110);
DISPLAY INVISIBLE (135 110);
FORCEPROP 1 LAST PATH I122
J 0
(200 50);
DISPLAY 0.872340 (200 50);
PAINT AQUA (200 50);
DISPLAY INVISIBLE (200 50);
FORCEPROP 1 LAST HDL_POWER GND
J 1
(150 -25);
DISPLAY 0.872340 (150 -25);
PAINT GREEN (150 -25);
DISPLAY INVISIBLE (150 -25);
FORCEPROP 2 LAST CDS_LIB logical_power
J 0
(125 50);
PAINT MONO (125 50);
DISPLAY INVISIBLE (125 50);
FORCEADD UNIVERSAL_GND..1
(1750 50);
FORCEPROP 3 LASTPIN (1750 100) SIG_NAME GND\g
J 0
(1760 110);
DISPLAY 0.659574 (1760 110);
PAINT MONO (1760 110);
DISPLAY INVISIBLE (1760 110);
FORCEPROP 1 LAST PATH I123
J 0
(1825 50);
DISPLAY 0.872340 (1825 50);
PAINT AQUA (1825 50);
DISPLAY INVISIBLE (1825 50);
FORCEPROP 1 LAST HDL_POWER GND
J 1
(1775 -25);
DISPLAY 0.872340 (1775 -25);
PAINT GREEN (1775 -25);
DISPLAY INVISIBLE (1775 -25);
FORCEPROP 2 LAST CDS_LIB logical_power
J 0
(1750 50);
PAINT MONO (1750 50);
DISPLAY INVISIBLE (1750 50);
FORCEADD Q_CAP..1
(125 425);
FORCEPROP 1 LAST PART_NUMBER CH5221MEB00
J 0
(175 275);
DISPLAY 0.978723 (175 275);
DISPLAY INVISIBLE (175 275);
FORCEPROP 1 LAST VOLTAGE 6.3V
J 0
(175 425);
DISPLAY 0.978723 (175 425);
FORCEPROP 1 LAST TOLERANCE 20%
J 0
(175 375);
DISPLAY 0.978723 (175 375);
FORCEPROP 1 LAST VALUE 2.2UF
J 0
(175 475);
DISPLAY 0.978723 (175 475);
FORCEPROP 1 LAST MATERIAL X6S
J 0
(175 325);
DISPLAY 0.978723 (175 325);
FORCEPROP 1 LAST PACK_TYPE C0402
J 0
(175 225);
DISPLAY 0.978723 (175 225);
FORCEPROP 1 LAST $LOCATION C75
J 0
(175 525);
DISPLAY 0.978723 (175 525);
FORCEPROP 1 LASTPIN (125 525) $PN 1
J 0
(135 505);
DISPLAY 0.787234 (135 505);
FORCEPROP 1 LASTPIN (125 325) $PN 2
J 0
(135 305);
DISPLAY 0.787234 (135 305);
FORCEPROP 2 LAST CDS_LIB pure_quanta
J 0
(125 425);
PAINT MONO (125 425);
DISPLAY INVISIBLE (125 425);
FORCEPROP 1 LAST PATH I124
J 0
(175 575);
DISPLAY 0.978723 (175 575);
PAINT WHITE (175 575);
DISPLAY INVISIBLE (175 575);
FORCEPROP 1 LAST $LOCATION C75
J 0
(175 625);
DISPLAY 1.021277 (175 625);
DISPLAY INVISIBLE (175 625);
FORCEPROP 2 LAST CDS_LOCATION C75
J 0
(175 625);
DISPLAY 1.021277 (175 625);
DISPLAY INVISIBLE (175 625);
FORCEPROP 2 LAST $SEC 1
J 0
(175 625);
DISPLAY 0.680851 (175 625);
PAINT MONO (175 625);
DISPLAY INVISIBLE (175 625);
FORCEPROP 2 LAST CDS_SEC 1
J 0
(175 625);
DISPLAY 1.021277 (175 625);
DISPLAY INVISIBLE (175 625);
FORCEADD Q_CAP..1
(1125 425);
FORCEPROP 1 LAST PART_NUMBER CH6103KEA00
J 0
(1175 275);
DISPLAY 0.978723 (1175 275);
DISPLAY INVISIBLE (1175 275);
FORCEPROP 1 LAST VOLTAGE 16V
J 0
(1175 425);
DISPLAY 0.978723 (1175 425);
FORCEPROP 1 LAST PACK_TYPE C0805
J 0
(1175 225);
DISPLAY 0.978723 (1175 225);
FORCEPROP 1 LAST TOLERANCE 10%
J 0
(1175 375);
DISPLAY 0.978723 (1175 375);
FORCEPROP 1 LAST VALUE 10UF
J 0
(1175 475);
DISPLAY 0.978723 (1175 475);
FORCEPROP 1 LAST MATERIAL X6S
J 0
(1175 325);
DISPLAY 0.978723 (1175 325);
FORCEPROP 1 LAST $LOCATION C76
J 0
(1175 525);
DISPLAY 0.978723 (1175 525);
FORCEPROP 1 LASTPIN (1125 525) $PN 1
J 0
(1135 505);
DISPLAY 0.787234 (1135 505);
FORCEPROP 1 LASTPIN (1125 325) $PN 2
J 0
(1135 305);
DISPLAY 0.787234 (1135 305);
FORCEPROP 2 LAST CDS_LIB pure_quanta
J 0
(1125 425);
PAINT MONO (1125 425);
DISPLAY INVISIBLE (1125 425);
FORCEPROP 1 LAST PATH I125
J 0
(1175 575);
DISPLAY 0.978723 (1175 575);
PAINT WHITE (1175 575);
DISPLAY INVISIBLE (1175 575);
FORCEPROP 1 LAST $LOCATION C76
J 0
(1175 625);
DISPLAY 1.021277 (1175 625);
DISPLAY INVISIBLE (1175 625);
FORCEPROP 2 LAST CDS_LOCATION C76
J 0
(1175 625);
DISPLAY 1.021277 (1175 625);
DISPLAY INVISIBLE (1175 625);
FORCEPROP 2 LAST $SEC 1
J 0
(1175 625);
DISPLAY 0.680851 (1175 625);
PAINT MONO (1175 625);
DISPLAY INVISIBLE (1175 625);
FORCEPROP 2 LAST CDS_SEC 1
J 0
(1175 625);
DISPLAY 1.021277 (1175 625);
DISPLAY INVISIBLE (1175 625);
FORCEADD Q_CAP..1
(1750 425);
FORCEPROP 1 LAST PART_NUMBER CH6103KEA00
J 0
(1800 275);
DISPLAY 0.978723 (1800 275);
DISPLAY INVISIBLE (1800 275);
FORCEPROP 1 LAST VOLTAGE 16V
J 0
(1800 425);
DISPLAY 0.978723 (1800 425);
FORCEPROP 1 LAST TOLERANCE 10%
J 0
(1800 375);
DISPLAY 0.978723 (1800 375);
FORCEPROP 1 LAST VALUE 10UF
J 0
(1800 475);
DISPLAY 0.978723 (1800 475);
FORCEPROP 1 LAST PACK_TYPE C0805
J 0
(1800 225);
DISPLAY 0.978723 (1800 225);
FORCEPROP 1 LAST MATERIAL X6S
J 0
(1800 325);
DISPLAY 0.978723 (1800 325);
FORCEPROP 1 LAST $LOCATION C77
J 0
(1800 525);
DISPLAY 0.978723 (1800 525);
FORCEPROP 1 LASTPIN (1750 525) $PN 1
J 0
(1760 505);
DISPLAY 0.787234 (1760 505);
FORCEPROP 1 LASTPIN (1750 325) $PN 2
J 0
(1760 305);
DISPLAY 0.787234 (1760 305);
FORCEPROP 2 LAST CDS_LIB pure_quanta
J 0
(1750 425);
PAINT MONO (1750 425);
DISPLAY INVISIBLE (1750 425);
FORCEPROP 1 LAST PATH I126
J 0
(1800 575);
DISPLAY 0.978723 (1800 575);
PAINT WHITE (1800 575);
DISPLAY INVISIBLE (1800 575);
FORCEPROP 1 LAST $LOCATION C77
J 0
(1800 625);
DISPLAY 1.021277 (1800 625);
DISPLAY INVISIBLE (1800 625);
FORCEPROP 2 LAST CDS_LOCATION C77
J 0
(1800 625);
DISPLAY 1.021277 (1800 625);
DISPLAY INVISIBLE (1800 625);
FORCEPROP 2 LAST $SEC 1
J 0
(1800 625);
DISPLAY 0.680851 (1800 625);
PAINT MONO (1800 625);
DISPLAY INVISIBLE (1800 625);
FORCEPROP 2 LAST CDS_SEC 1
J 0
(1800 625);
DISPLAY 1.021277 (1800 625);
DISPLAY INVISIBLE (1800 625);
FORCEADD VCC_CORE..1
(125 750);
FORCEPROP 3 LASTPIN (125 700) SIG_NAME P3V3_AUX\g
J 0
(135 710);
DISPLAY 0.659574 (135 710);
PAINT MONO (135 710);
DISPLAY INVISIBLE (135 710);
FORCEPROP 1 LAST HDL_POWER P3V3_AUX
J 1
(125 800);
DISPLAY 1.148936 (125 800);
PAINT GREEN (125 800);
FORCEPROP 2 LAST CDS_LIB logical_power
J 0
(125 750);
PAINT MONO (125 750);
DISPLAY INVISIBLE (125 750);
FORCEPROP 1 LAST PATH I127
J 0
(175 775);
DISPLAY 0.872340 (175 775);
PAINT AQUA (175 775);
DISPLAY INVISIBLE (175 775);
FORCEADD VCC_CORE..1
(1125 750);
FORCEPROP 3 LASTPIN (1125 700) SIG_NAME P12V_S3_AUX_CPU1_NVDIMM\g
J 0
(1135 710);
DISPLAY 0.659574 (1135 710);
PAINT MONO (1135 710);
DISPLAY INVISIBLE (1135 710);
FORCEPROP 1 LAST HDL_POWER P12V_S3_AUX_CPU1_NVDIMM
J 1
(1125 800);
DISPLAY 1.148936 (1125 800);
PAINT GREEN (1125 800);
FORCEPROP 2 LAST CDS_LIB logical_power
J 0
(1125 750);
PAINT MONO (1125 750);
DISPLAY INVISIBLE (1125 750);
FORCEPROP 1 LAST PATH I129
J 0
(1175 775);
DISPLAY 0.872340 (1175 775);
PAINT AQUA (1175 775);
DISPLAY INVISIBLE (1175 775);
FORCEADD TAP..1
(1325 2300);
FORCEPROP 3 LASTPIN (1275 2300) SIG_NAME M_H_CPU1_SB_DQS_DN<0>
J 0
(1285 2310);
DISPLAY 0.659574 (1285 2310);
PAINT MONO (1285 2310);
DISPLAY INVISIBLE (1285 2310);
FORCEPROP 1 LASTPIN (1275 2300) BN 0
J 0
(1263 2308);
DISPLAY 0.680851 (1263 2308);
PAINT GREEN (1263 2308);
FORCEPROP 2 LAST CDS_LIB standard
J 0
(1325 2300);
PAINT MONO (1325 2300);
DISPLAY INVISIBLE (1325 2300);
FORCEPROP 1 LAST BODY_TYPE PLUMBING
J 0
(1325 2350);
DISPLAY 0.872340 (1325 2350);
PAINT GREEN (1325 2350);
DISPLAY INVISIBLE (1325 2350);
FORCEPROP 1 LAST HDL_TAP TRUE
J 0
(1650 2175);
DISPLAY 0.872340 (1650 2175);
DISPLAY INVISIBLE (1650 2175);
FORCEPROP 1 LAST PATH I130
J 0
(1323 2300);
DISPLAY 0.872340 (1323 2300);
PAINT GREEN (1323 2300);
DISPLAY INVISIBLE (1323 2300);
FORCEADD TAP..1
(1150 2350);
FORCEPROP 3 LASTPIN (1100 2350) SIG_NAME M_H_CPU1_SB_DQS_DP<0>
J 0
(1110 2360);
DISPLAY 0.659574 (1110 2360);
PAINT MONO (1110 2360);
DISPLAY INVISIBLE (1110 2360);
FORCEPROP 1 LASTPIN (1100 2350) BN 0
J 0
(1088 2358);
DISPLAY 0.680851 (1088 2358);
PAINT GREEN (1088 2358);
FORCEPROP 2 LAST CDS_LIB standard
J 0
(1150 2350);
PAINT MONO (1150 2350);
DISPLAY INVISIBLE (1150 2350);
FORCEPROP 1 LAST BODY_TYPE PLUMBING
J 0
(1150 2400);
DISPLAY 0.872340 (1150 2400);
PAINT GREEN (1150 2400);
DISPLAY INVISIBLE (1150 2400);
FORCEPROP 1 LAST HDL_TAP TRUE
J 0
(1475 2225);
DISPLAY 0.872340 (1475 2225);
DISPLAY INVISIBLE (1475 2225);
FORCEPROP 1 LAST PATH I131
J 0
(1148 2350);
DISPLAY 0.872340 (1148 2350);
PAINT GREEN (1148 2350);
DISPLAY INVISIBLE (1148 2350);
FORCEADD TAP..1
(1150 2450);
FORCEPROP 3 LASTPIN (1100 2450) SIG_NAME M_H_CPU1_SB_DQS_DP<1>
J 0
(1110 2460);
DISPLAY 0.659574 (1110 2460);
PAINT MONO (1110 2460);
DISPLAY INVISIBLE (1110 2460);
FORCEPROP 1 LASTPIN (1100 2450) BN 1
J 0
(1088 2458);
DISPLAY 0.680851 (1088 2458);
PAINT GREEN (1088 2458);
FORCEPROP 2 LAST CDS_LIB standard
J 0
(1150 2450);
DISPLAY INVISIBLE (1150 2450);
FORCEPROP 1 LAST BODY_TYPE PLUMBING
J 0
(1150 2500);
DISPLAY 0.872340 (1150 2500);
PAINT GREEN (1150 2500);
DISPLAY INVISIBLE (1150 2500);
FORCEPROP 1 LAST HDL_TAP TRUE
J 0
(1475 2325);
DISPLAY 0.872340 (1475 2325);
DISPLAY INVISIBLE (1475 2325);
FORCEPROP 1 LAST PATH I132
J 0
(1148 2450);
DISPLAY 0.872340 (1148 2450);
PAINT GREEN (1148 2450);
DISPLAY INVISIBLE (1148 2450);
FORCEADD TAP..1
(1150 2550);
FORCEPROP 3 LASTPIN (1100 2550) SIG_NAME M_H_CPU1_SB_DQS_DP<2>
J 0
(1110 2560);
DISPLAY 0.659574 (1110 2560);
PAINT MONO (1110 2560);
DISPLAY INVISIBLE (1110 2560);
FORCEPROP 1 LASTPIN (1100 2550) BN 2
J 0
(1088 2558);
DISPLAY 0.680851 (1088 2558);
PAINT GREEN (1088 2558);
FORCEPROP 2 LAST CDS_LIB standard
J 0
(1150 2550);
DISPLAY INVISIBLE (1150 2550);
FORCEPROP 1 LAST BODY_TYPE PLUMBING
J 0
(1150 2600);
DISPLAY 0.872340 (1150 2600);
PAINT GREEN (1150 2600);
DISPLAY INVISIBLE (1150 2600);
FORCEPROP 1 LAST HDL_TAP TRUE
J 0
(1475 2425);
DISPLAY 0.872340 (1475 2425);
DISPLAY INVISIBLE (1475 2425);
FORCEPROP 1 LAST PATH I133
J 0
(1148 2550);
DISPLAY 0.872340 (1148 2550);
PAINT GREEN (1148 2550);
DISPLAY INVISIBLE (1148 2550);
FORCEADD TAP..1
(1325 2500);
FORCEPROP 3 LASTPIN (1275 2500) SIG_NAME M_H_CPU1_SB_DQS_DN<2>
J 0
(1285 2510);
DISPLAY 0.659574 (1285 2510);
PAINT MONO (1285 2510);
DISPLAY INVISIBLE (1285 2510);
FORCEPROP 1 LASTPIN (1275 2500) BN 2
J 0
(1263 2508);
DISPLAY 0.680851 (1263 2508);
PAINT GREEN (1263 2508);
FORCEPROP 2 LAST CDS_LIB standard
J 0
(1325 2500);
DISPLAY INVISIBLE (1325 2500);
FORCEPROP 1 LAST BODY_TYPE PLUMBING
J 0
(1325 2550);
DISPLAY 0.872340 (1325 2550);
PAINT GREEN (1325 2550);
DISPLAY INVISIBLE (1325 2550);
FORCEPROP 1 LAST HDL_TAP TRUE
J 0
(1650 2375);
DISPLAY 0.872340 (1650 2375);
DISPLAY INVISIBLE (1650 2375);
FORCEPROP 1 LAST PATH I134
J 0
(1323 2500);
DISPLAY 0.872340 (1323 2500);
PAINT GREEN (1323 2500);
DISPLAY INVISIBLE (1323 2500);
FORCEADD TAP..1
(1325 2400);
FORCEPROP 3 LASTPIN (1275 2400) SIG_NAME M_H_CPU1_SB_DQS_DN<1>
J 0
(1285 2410);
DISPLAY 0.659574 (1285 2410);
PAINT MONO (1285 2410);
DISPLAY INVISIBLE (1285 2410);
FORCEPROP 1 LASTPIN (1275 2400) BN 1
J 0
(1263 2408);
DISPLAY 0.680851 (1263 2408);
PAINT GREEN (1263 2408);
FORCEPROP 2 LAST CDS_LIB standard
J 0
(1325 2400);
DISPLAY INVISIBLE (1325 2400);
FORCEPROP 1 LAST BODY_TYPE PLUMBING
J 0
(1325 2450);
DISPLAY 0.872340 (1325 2450);
PAINT GREEN (1325 2450);
DISPLAY INVISIBLE (1325 2450);
FORCEPROP 1 LAST HDL_TAP TRUE
J 0
(1650 2275);
DISPLAY 0.872340 (1650 2275);
DISPLAY INVISIBLE (1650 2275);
FORCEPROP 1 LAST PATH I135
J 0
(1323 2400);
DISPLAY 0.872340 (1323 2400);
PAINT GREEN (1323 2400);
DISPLAY INVISIBLE (1323 2400);
FORCEADD TAP..1
(1325 2600);
FORCEPROP 3 LASTPIN (1275 2600) SIG_NAME M_H_CPU1_SB_DQS_DN<3>
J 0
(1285 2610);
DISPLAY 0.659574 (1285 2610);
PAINT MONO (1285 2610);
DISPLAY INVISIBLE (1285 2610);
FORCEPROP 1 LASTPIN (1275 2600) BN 3
J 0
(1263 2608);
DISPLAY 0.680851 (1263 2608);
PAINT GREEN (1263 2608);
FORCEPROP 2 LAST CDS_LIB standard
J 0
(1325 2600);
PAINT MONO (1325 2600);
DISPLAY INVISIBLE (1325 2600);
FORCEPROP 1 LAST BODY_TYPE PLUMBING
J 0
(1325 2650);
DISPLAY 0.872340 (1325 2650);
PAINT GREEN (1325 2650);
DISPLAY INVISIBLE (1325 2650);
FORCEPROP 1 LAST HDL_TAP TRUE
J 0
(1650 2475);
DISPLAY 0.872340 (1650 2475);
DISPLAY INVISIBLE (1650 2475);
FORCEPROP 1 LAST PATH I136
J 0
(1323 2600);
DISPLAY 0.872340 (1323 2600);
PAINT GREEN (1323 2600);
DISPLAY INVISIBLE (1323 2600);
FORCEADD TAP..1
(1150 2650);
FORCEPROP 3 LASTPIN (1100 2650) SIG_NAME M_H_CPU1_SB_DQS_DP<3>
J 0
(1110 2660);
DISPLAY 0.659574 (1110 2660);
PAINT MONO (1110 2660);
DISPLAY INVISIBLE (1110 2660);
FORCEPROP 1 LASTPIN (1100 2650) BN 3
J 0
(1088 2658);
DISPLAY 0.680851 (1088 2658);
PAINT GREEN (1088 2658);
FORCEPROP 2 LAST CDS_LIB standard
J 0
(1150 2650);
PAINT MONO (1150 2650);
DISPLAY INVISIBLE (1150 2650);
FORCEPROP 1 LAST BODY_TYPE PLUMBING
J 0
(1150 2700);
DISPLAY 0.872340 (1150 2700);
PAINT GREEN (1150 2700);
DISPLAY INVISIBLE (1150 2700);
FORCEPROP 1 LAST HDL_TAP TRUE
J 0
(1475 2525);
DISPLAY 0.872340 (1475 2525);
DISPLAY INVISIBLE (1475 2525);
FORCEPROP 1 LAST PATH I137
J 0
(1148 2650);
DISPLAY 0.872340 (1148 2650);
PAINT GREEN (1148 2650);
DISPLAY INVISIBLE (1148 2650);
FORCEADD TAP..1
(1150 2750);
FORCEPROP 3 LASTPIN (1100 2750) SIG_NAME M_H_CPU1_SB_DQS_DP<4>
J 0
(1110 2760);
DISPLAY 0.659574 (1110 2760);
PAINT MONO (1110 2760);
DISPLAY INVISIBLE (1110 2760);
FORCEPROP 1 LASTPIN (1100 2750) BN 4
J 0
(1088 2758);
DISPLAY 0.680851 (1088 2758);
PAINT GREEN (1088 2758);
FORCEPROP 2 LAST CDS_LIB standard
J 0
(1150 2750);
PAINT MONO (1150 2750);
DISPLAY INVISIBLE (1150 2750);
FORCEPROP 1 LAST BODY_TYPE PLUMBING
J 0
(1150 2800);
DISPLAY 0.872340 (1150 2800);
PAINT GREEN (1150 2800);
DISPLAY INVISIBLE (1150 2800);
FORCEPROP 1 LAST HDL_TAP TRUE
J 0
(1475 2625);
DISPLAY 0.872340 (1475 2625);
DISPLAY INVISIBLE (1475 2625);
FORCEPROP 1 LAST PATH I138
J 0
(1148 2750);
DISPLAY 0.872340 (1148 2750);
PAINT GREEN (1148 2750);
DISPLAY INVISIBLE (1148 2750);
FORCEADD TAP..1
(1150 2850);
FORCEPROP 3 LASTPIN (1100 2850) SIG_NAME M_H_CPU1_SB_DQS_DP<5>
J 0
(1110 2860);
DISPLAY 0.659574 (1110 2860);
PAINT MONO (1110 2860);
DISPLAY INVISIBLE (1110 2860);
FORCEPROP 1 LASTPIN (1100 2850) BN 5
J 0
(1088 2858);
DISPLAY 0.680851 (1088 2858);
PAINT GREEN (1088 2858);
FORCEPROP 2 LAST CDS_LIB standard
J 0
(1150 2850);
DISPLAY INVISIBLE (1150 2850);
FORCEPROP 1 LAST BODY_TYPE PLUMBING
J 0
(1150 2900);
DISPLAY 0.872340 (1150 2900);
PAINT GREEN (1150 2900);
DISPLAY INVISIBLE (1150 2900);
FORCEPROP 1 LAST HDL_TAP TRUE
J 0
(1475 2725);
DISPLAY 0.872340 (1475 2725);
DISPLAY INVISIBLE (1475 2725);
FORCEPROP 1 LAST PATH I139
J 0
(1148 2850);
DISPLAY 0.872340 (1148 2850);
PAINT GREEN (1148 2850);
DISPLAY INVISIBLE (1148 2850);
FORCEADD TAP..1
R 2
(-3250 2100);
FORCEPROP 3 LASTPIN (-3200 2100) SIG_NAME M_H_CPU1_SB_CB<0>
J 0
(-3190 2110);
DISPLAY 0.659574 (-3190 2110);
PAINT MONO (-3190 2110);
DISPLAY INVISIBLE (-3190 2110);
FORCEPROP 1 LASTPIN (-3200 2100) BN 0
J 2
(-3188 2108);
DISPLAY 0.680851 (-3188 2108);
PAINT GREEN (-3188 2108);
FORCEPROP 2 LAST CDS_LIB standard
J 0
(-3250 2100);
PAINT MONO (-3250 2100);
DISPLAY INVISIBLE (-3250 2100);
FORCEPROP 1 LAST BODY_TYPE PLUMBING
J 2
(-3250 2150);
DISPLAY 0.872340 (-3250 2150);
PAINT GREEN (-3250 2150);
DISPLAY INVISIBLE (-3250 2150);
FORCEPROP 1 LAST HDL_TAP TRUE
J 2
(-3575 1975);
DISPLAY 0.872340 (-3575 1975);
DISPLAY INVISIBLE (-3575 1975);
FORCEPROP 1 LAST PATH I14
J 2
(-3248 2100);
DISPLAY 0.872340 (-3248 2100);
PAINT GREEN (-3248 2100);
DISPLAY INVISIBLE (-3248 2100);
FORCEADD TAP..1
(1325 2700);
FORCEPROP 3 LASTPIN (1275 2700) SIG_NAME M_H_CPU1_SB_DQS_DN<4>
J 0
(1285 2710);
DISPLAY 0.659574 (1285 2710);
PAINT MONO (1285 2710);
DISPLAY INVISIBLE (1285 2710);
FORCEPROP 1 LASTPIN (1275 2700) BN 4
J 0
(1263 2708);
DISPLAY 0.680851 (1263 2708);
PAINT GREEN (1263 2708);
FORCEPROP 2 LAST CDS_LIB standard
J 0
(1325 2700);
PAINT MONO (1325 2700);
DISPLAY INVISIBLE (1325 2700);
FORCEPROP 1 LAST BODY_TYPE PLUMBING
J 0
(1325 2750);
DISPLAY 0.872340 (1325 2750);
PAINT GREEN (1325 2750);
DISPLAY INVISIBLE (1325 2750);
FORCEPROP 1 LAST HDL_TAP TRUE
J 0
(1650 2575);
DISPLAY 0.872340 (1650 2575);
DISPLAY INVISIBLE (1650 2575);
FORCEPROP 1 LAST PATH I140
J 0
(1323 2700);
DISPLAY 0.872340 (1323 2700);
PAINT GREEN (1323 2700);
DISPLAY INVISIBLE (1323 2700);
FORCEADD TAP..1
(1325 2800);
FORCEPROP 3 LASTPIN (1275 2800) SIG_NAME M_H_CPU1_SB_DQS_DN<5>
J 0
(1285 2810);
DISPLAY 0.659574 (1285 2810);
PAINT MONO (1285 2810);
DISPLAY INVISIBLE (1285 2810);
FORCEPROP 1 LASTPIN (1275 2800) BN 5
J 0
(1263 2808);
DISPLAY 0.680851 (1263 2808);
PAINT GREEN (1263 2808);
FORCEPROP 2 LAST CDS_LIB standard
J 0
(1325 2800);
DISPLAY INVISIBLE (1325 2800);
FORCEPROP 1 LAST BODY_TYPE PLUMBING
J 0
(1325 2850);
DISPLAY 0.872340 (1325 2850);
PAINT GREEN (1325 2850);
DISPLAY INVISIBLE (1325 2850);
FORCEPROP 1 LAST HDL_TAP TRUE
J 0
(1650 2675);
DISPLAY 0.872340 (1650 2675);
DISPLAY INVISIBLE (1650 2675);
FORCEPROP 1 LAST PATH I141
J 0
(1323 2800);
DISPLAY 0.872340 (1323 2800);
PAINT GREEN (1323 2800);
DISPLAY INVISIBLE (1323 2800);
FORCEADD TAP..1
(1150 2950);
FORCEPROP 3 LASTPIN (1100 2950) SIG_NAME M_H_CPU1_SB_DQS_DP<6>
J 0
(1110 2960);
DISPLAY 0.659574 (1110 2960);
PAINT MONO (1110 2960);
DISPLAY INVISIBLE (1110 2960);
FORCEPROP 1 LASTPIN (1100 2950) BN 6
J 0
(1088 2958);
DISPLAY 0.680851 (1088 2958);
PAINT GREEN (1088 2958);
FORCEPROP 2 LAST CDS_LIB standard
J 0
(1150 2950);
DISPLAY INVISIBLE (1150 2950);
FORCEPROP 1 LAST BODY_TYPE PLUMBING
J 0
(1150 3000);
DISPLAY 0.872340 (1150 3000);
PAINT GREEN (1150 3000);
DISPLAY INVISIBLE (1150 3000);
FORCEPROP 1 LAST HDL_TAP TRUE
J 0
(1475 2825);
DISPLAY 0.872340 (1475 2825);
DISPLAY INVISIBLE (1475 2825);
FORCEPROP 1 LAST PATH I142
J 0
(1148 2950);
DISPLAY 0.872340 (1148 2950);
PAINT GREEN (1148 2950);
DISPLAY INVISIBLE (1148 2950);
FORCEADD TAP..1
(1150 3050);
FORCEPROP 3 LASTPIN (1100 3050) SIG_NAME M_H_CPU1_SB_DQS_DP<7>
J 0
(1110 3060);
DISPLAY 0.659574 (1110 3060);
PAINT MONO (1110 3060);
DISPLAY INVISIBLE (1110 3060);
FORCEPROP 1 LASTPIN (1100 3050) BN 7
J 0
(1088 3058);
DISPLAY 0.680851 (1088 3058);
PAINT GREEN (1088 3058);
FORCEPROP 2 LAST CDS_LIB standard
J 0
(1150 3050);
DISPLAY INVISIBLE (1150 3050);
FORCEPROP 1 LAST BODY_TYPE PLUMBING
J 0
(1150 3100);
DISPLAY 0.872340 (1150 3100);
PAINT GREEN (1150 3100);
DISPLAY INVISIBLE (1150 3100);
FORCEPROP 1 LAST HDL_TAP TRUE
J 0
(1475 2925);
DISPLAY 0.872340 (1475 2925);
DISPLAY INVISIBLE (1475 2925);
FORCEPROP 1 LAST PATH I143
J 0
(1148 3050);
DISPLAY 0.872340 (1148 3050);
PAINT GREEN (1148 3050);
DISPLAY INVISIBLE (1148 3050);
FORCEADD TAP..1
(1325 3000);
FORCEPROP 3 LASTPIN (1275 3000) SIG_NAME M_H_CPU1_SB_DQS_DN<7>
J 0
(1285 3010);
DISPLAY 0.659574 (1285 3010);
PAINT MONO (1285 3010);
DISPLAY INVISIBLE (1285 3010);
FORCEPROP 1 LASTPIN (1275 3000) BN 7
J 0
(1263 3008);
DISPLAY 0.680851 (1263 3008);
PAINT GREEN (1263 3008);
FORCEPROP 2 LAST CDS_LIB standard
J 0
(1325 3000);
DISPLAY INVISIBLE (1325 3000);
FORCEPROP 1 LAST BODY_TYPE PLUMBING
J 0
(1325 3050);
DISPLAY 0.872340 (1325 3050);
PAINT GREEN (1325 3050);
DISPLAY INVISIBLE (1325 3050);
FORCEPROP 1 LAST HDL_TAP TRUE
J 0
(1650 2875);
DISPLAY 0.872340 (1650 2875);
DISPLAY INVISIBLE (1650 2875);
FORCEPROP 1 LAST PATH I144
J 0
(1323 3000);
DISPLAY 0.872340 (1323 3000);
PAINT GREEN (1323 3000);
DISPLAY INVISIBLE (1323 3000);
FORCEADD TAP..1
(1325 2900);
FORCEPROP 3 LASTPIN (1275 2900) SIG_NAME M_H_CPU1_SB_DQS_DN<6>
J 0
(1285 2910);
DISPLAY 0.659574 (1285 2910);
PAINT MONO (1285 2910);
DISPLAY INVISIBLE (1285 2910);
FORCEPROP 1 LASTPIN (1275 2900) BN 6
J 0
(1263 2908);
DISPLAY 0.680851 (1263 2908);
PAINT GREEN (1263 2908);
FORCEPROP 2 LAST CDS_LIB standard
J 0
(1325 2900);
DISPLAY INVISIBLE (1325 2900);
FORCEPROP 1 LAST BODY_TYPE PLUMBING
J 0
(1325 2950);
DISPLAY 0.872340 (1325 2950);
PAINT GREEN (1325 2950);
DISPLAY INVISIBLE (1325 2950);
FORCEPROP 1 LAST HDL_TAP TRUE
J 0
(1650 2775);
DISPLAY 0.872340 (1650 2775);
DISPLAY INVISIBLE (1650 2775);
FORCEPROP 1 LAST PATH I145
J 0
(1323 2900);
DISPLAY 0.872340 (1323 2900);
PAINT GREEN (1323 2900);
DISPLAY INVISIBLE (1323 2900);
FORCEADD TAP..1
(1325 3100);
FORCEPROP 3 LASTPIN (1275 3100) SIG_NAME M_H_CPU1_SB_DQS_DN<8>
J 0
(1285 3110);
DISPLAY 0.659574 (1285 3110);
PAINT MONO (1285 3110);
DISPLAY INVISIBLE (1285 3110);
FORCEPROP 1 LASTPIN (1275 3100) BN 8
J 0
(1263 3108);
DISPLAY 0.680851 (1263 3108);
PAINT GREEN (1263 3108);
FORCEPROP 2 LAST CDS_LIB standard
J 0
(1325 3100);
DISPLAY INVISIBLE (1325 3100);
FORCEPROP 1 LAST BODY_TYPE PLUMBING
J 0
(1325 3150);
DISPLAY 0.872340 (1325 3150);
PAINT GREEN (1325 3150);
DISPLAY INVISIBLE (1325 3150);
FORCEPROP 1 LAST HDL_TAP TRUE
J 0
(1650 2975);
DISPLAY 0.872340 (1650 2975);
DISPLAY INVISIBLE (1650 2975);
FORCEPROP 1 LAST PATH I146
J 0
(1323 3100);
DISPLAY 0.872340 (1323 3100);
PAINT GREEN (1323 3100);
DISPLAY INVISIBLE (1323 3100);
FORCEADD TAP..1
(1150 3150);
FORCEPROP 3 LASTPIN (1100 3150) SIG_NAME M_H_CPU1_SB_DQS_DP<8>
J 0
(1110 3160);
DISPLAY 0.659574 (1110 3160);
PAINT MONO (1110 3160);
DISPLAY INVISIBLE (1110 3160);
FORCEPROP 1 LASTPIN (1100 3150) BN 8
J 0
(1088 3158);
DISPLAY 0.680851 (1088 3158);
PAINT GREEN (1088 3158);
FORCEPROP 2 LAST CDS_LIB standard
J 0
(1150 3150);
DISPLAY INVISIBLE (1150 3150);
FORCEPROP 1 LAST BODY_TYPE PLUMBING
J 0
(1150 3200);
DISPLAY 0.872340 (1150 3200);
PAINT GREEN (1150 3200);
DISPLAY INVISIBLE (1150 3200);
FORCEPROP 1 LAST HDL_TAP TRUE
J 0
(1475 3025);
DISPLAY 0.872340 (1475 3025);
DISPLAY INVISIBLE (1475 3025);
FORCEPROP 1 LAST PATH I147
J 0
(1148 3150);
DISPLAY 0.872340 (1148 3150);
PAINT GREEN (1148 3150);
DISPLAY INVISIBLE (1148 3150);
FORCEADD TAP..1
(1150 3250);
FORCEPROP 3 LASTPIN (1100 3250) SIG_NAME M_H_CPU1_SB_DQS_DP<9>
J 0
(1110 3260);
DISPLAY 0.659574 (1110 3260);
PAINT MONO (1110 3260);
DISPLAY INVISIBLE (1110 3260);
FORCEPROP 1 LASTPIN (1100 3250) BN 9
J 0
(1088 3258);
DISPLAY 0.680851 (1088 3258);
PAINT GREEN (1088 3258);
FORCEPROP 2 LAST CDS_LIB standard
J 0
(1150 3250);
DISPLAY INVISIBLE (1150 3250);
FORCEPROP 1 LAST BODY_TYPE PLUMBING
J 0
(1150 3300);
DISPLAY 0.872340 (1150 3300);
PAINT GREEN (1150 3300);
DISPLAY INVISIBLE (1150 3300);
FORCEPROP 1 LAST HDL_TAP TRUE
J 0
(1475 3125);
DISPLAY 0.872340 (1475 3125);
DISPLAY INVISIBLE (1475 3125);
FORCEPROP 1 LAST PATH I148
J 0
(1148 3250);
DISPLAY 0.872340 (1148 3250);
PAINT GREEN (1148 3250);
DISPLAY INVISIBLE (1148 3250);
FORCEADD TAP..1
(1325 3350);
FORCEPROP 3 LASTPIN (1275 3350) SIG_NAME M_H_CPU1_SA_DQS_DN<0>
J 0
(1285 3360);
DISPLAY 0.659574 (1285 3360);
PAINT MONO (1285 3360);
DISPLAY INVISIBLE (1285 3360);
FORCEPROP 1 LASTPIN (1275 3350) BN 0
J 0
(1263 3358);
DISPLAY 0.680851 (1263 3358);
PAINT GREEN (1263 3358);
FORCEPROP 2 LAST CDS_LIB standard
J 0
(1325 3350);
PAINT MONO (1325 3350);
DISPLAY INVISIBLE (1325 3350);
FORCEPROP 1 LAST BODY_TYPE PLUMBING
J 0
(1325 3400);
DISPLAY 0.872340 (1325 3400);
PAINT GREEN (1325 3400);
DISPLAY INVISIBLE (1325 3400);
FORCEPROP 1 LAST HDL_TAP TRUE
J 0
(1650 3225);
DISPLAY 0.872340 (1650 3225);
DISPLAY INVISIBLE (1650 3225);
FORCEPROP 1 LAST PATH I149
J 0
(1323 3350);
DISPLAY 0.872340 (1323 3350);
PAINT GREEN (1323 3350);
DISPLAY INVISIBLE (1323 3350);
FORCEADD TAP..1
R 2
(-3250 2150);
FORCEPROP 3 LASTPIN (-3200 2150) SIG_NAME M_H_CPU1_SB_CB<1>
J 0
(-3190 2160);
DISPLAY 0.659574 (-3190 2160);
PAINT MONO (-3190 2160);
DISPLAY INVISIBLE (-3190 2160);
FORCEPROP 1 LASTPIN (-3200 2150) BN 1
J 2
(-3188 2158);
DISPLAY 0.680851 (-3188 2158);
PAINT GREEN (-3188 2158);
FORCEPROP 2 LAST CDS_LIB standard
J 0
(-3250 2150);
DISPLAY INVISIBLE (-3250 2150);
FORCEPROP 1 LAST BODY_TYPE PLUMBING
J 2
(-3250 2200);
DISPLAY 0.872340 (-3250 2200);
PAINT GREEN (-3250 2200);
DISPLAY INVISIBLE (-3250 2200);
FORCEPROP 1 LAST HDL_TAP TRUE
J 2
(-3575 2025);
DISPLAY 0.872340 (-3575 2025);
DISPLAY INVISIBLE (-3575 2025);
FORCEPROP 1 LAST PATH I15
J 2
(-3248 2150);
DISPLAY 0.872340 (-3248 2150);
PAINT GREEN (-3248 2150);
DISPLAY INVISIBLE (-3248 2150);
FORCEADD TAP..1
(1325 3200);
FORCEPROP 3 LASTPIN (1275 3200) SIG_NAME M_H_CPU1_SB_DQS_DN<9>
J 0
(1285 3210);
DISPLAY 0.659574 (1285 3210);
PAINT MONO (1285 3210);
DISPLAY INVISIBLE (1285 3210);
FORCEPROP 1 LASTPIN (1275 3200) BN 9
J 0
(1263 3208);
DISPLAY 0.680851 (1263 3208);
PAINT GREEN (1263 3208);
FORCEPROP 2 LAST CDS_LIB standard
J 0
(1325 3200);
DISPLAY INVISIBLE (1325 3200);
FORCEPROP 1 LAST BODY_TYPE PLUMBING
J 0
(1325 3250);
DISPLAY 0.872340 (1325 3250);
PAINT GREEN (1325 3250);
DISPLAY INVISIBLE (1325 3250);
FORCEPROP 1 LAST HDL_TAP TRUE
J 0
(1650 3075);
DISPLAY 0.872340 (1650 3075);
DISPLAY INVISIBLE (1650 3075);
FORCEPROP 1 LAST PATH I150
J 0
(1323 3200);
DISPLAY 0.872340 (1323 3200);
PAINT GREEN (1323 3200);
DISPLAY INVISIBLE (1323 3200);
FORCEADD TAP..1
(1150 3500);
FORCEPROP 3 LASTPIN (1100 3500) SIG_NAME M_H_CPU1_SA_DQS_DP<1>
J 0
(1110 3510);
DISPLAY 0.659574 (1110 3510);
PAINT MONO (1110 3510);
DISPLAY INVISIBLE (1110 3510);
FORCEPROP 1 LASTPIN (1100 3500) BN 1
J 0
(1088 3508);
DISPLAY 0.680851 (1088 3508);
PAINT GREEN (1088 3508);
FORCEPROP 2 LAST CDS_LIB standard
J 0
(1150 3500);
DISPLAY INVISIBLE (1150 3500);
FORCEPROP 1 LAST BODY_TYPE PLUMBING
J 0
(1150 3550);
DISPLAY 0.872340 (1150 3550);
PAINT GREEN (1150 3550);
DISPLAY INVISIBLE (1150 3550);
FORCEPROP 1 LAST HDL_TAP TRUE
J 0
(1475 3375);
DISPLAY 0.872340 (1475 3375);
DISPLAY INVISIBLE (1475 3375);
FORCEPROP 1 LAST PATH I151
J 0
(1148 3500);
DISPLAY 0.872340 (1148 3500);
PAINT GREEN (1148 3500);
DISPLAY INVISIBLE (1148 3500);
FORCEADD TAP..1
(1150 3400);
FORCEPROP 3 LASTPIN (1100 3400) SIG_NAME M_H_CPU1_SA_DQS_DP<0>
J 0
(1110 3410);
DISPLAY 0.659574 (1110 3410);
PAINT MONO (1110 3410);
DISPLAY INVISIBLE (1110 3410);
FORCEPROP 1 LASTPIN (1100 3400) BN 0
J 0
(1088 3408);
DISPLAY 0.680851 (1088 3408);
PAINT GREEN (1088 3408);
FORCEPROP 2 LAST CDS_LIB standard
J 0
(1150 3400);
PAINT MONO (1150 3400);
DISPLAY INVISIBLE (1150 3400);
FORCEPROP 1 LAST BODY_TYPE PLUMBING
J 0
(1150 3450);
DISPLAY 0.872340 (1150 3450);
PAINT GREEN (1150 3450);
DISPLAY INVISIBLE (1150 3450);
FORCEPROP 1 LAST HDL_TAP TRUE
J 0
(1475 3275);
DISPLAY 0.872340 (1475 3275);
DISPLAY INVISIBLE (1475 3275);
FORCEPROP 1 LAST PATH I152
J 0
(1148 3400);
DISPLAY 0.872340 (1148 3400);
PAINT GREEN (1148 3400);
DISPLAY INVISIBLE (1148 3400);
FORCEADD TAP..1
(1150 3600);
FORCEPROP 3 LASTPIN (1100 3600) SIG_NAME M_H_CPU1_SA_DQS_DP<2>
J 0
(1110 3610);
DISPLAY 0.659574 (1110 3610);
PAINT MONO (1110 3610);
DISPLAY INVISIBLE (1110 3610);
FORCEPROP 1 LASTPIN (1100 3600) BN 2
J 0
(1088 3608);
DISPLAY 0.680851 (1088 3608);
PAINT GREEN (1088 3608);
FORCEPROP 2 LAST CDS_LIB standard
J 0
(1150 3600);
DISPLAY INVISIBLE (1150 3600);
FORCEPROP 1 LAST BODY_TYPE PLUMBING
J 0
(1150 3650);
DISPLAY 0.872340 (1150 3650);
PAINT GREEN (1150 3650);
DISPLAY INVISIBLE (1150 3650);
FORCEPROP 1 LAST HDL_TAP TRUE
J 0
(1475 3475);
DISPLAY 0.872340 (1475 3475);
DISPLAY INVISIBLE (1475 3475);
FORCEPROP 1 LAST PATH I153
J 0
(1148 3600);
DISPLAY 0.872340 (1148 3600);
PAINT GREEN (1148 3600);
DISPLAY INVISIBLE (1148 3600);
FORCEADD TAP..1
(1325 3450);
FORCEPROP 3 LASTPIN (1275 3450) SIG_NAME M_H_CPU1_SA_DQS_DN<1>
J 0
(1285 3460);
DISPLAY 0.659574 (1285 3460);
PAINT MONO (1285 3460);
DISPLAY INVISIBLE (1285 3460);
FORCEPROP 1 LASTPIN (1275 3450) BN 1
J 0
(1263 3458);
DISPLAY 0.680851 (1263 3458);
PAINT GREEN (1263 3458);
FORCEPROP 2 LAST CDS_LIB standard
J 0
(1325 3450);
DISPLAY INVISIBLE (1325 3450);
FORCEPROP 1 LAST BODY_TYPE PLUMBING
J 0
(1325 3500);
DISPLAY 0.872340 (1325 3500);
PAINT GREEN (1325 3500);
DISPLAY INVISIBLE (1325 3500);
FORCEPROP 1 LAST HDL_TAP TRUE
J 0
(1650 3325);
DISPLAY 0.872340 (1650 3325);
DISPLAY INVISIBLE (1650 3325);
FORCEPROP 1 LAST PATH I154
J 0
(1323 3450);
DISPLAY 0.872340 (1323 3450);
PAINT GREEN (1323 3450);
DISPLAY INVISIBLE (1323 3450);
FORCEADD TAP..1
(1325 3650);
FORCEPROP 3 LASTPIN (1275 3650) SIG_NAME M_H_CPU1_SA_DQS_DN<3>
J 0
(1285 3660);
DISPLAY 0.659574 (1285 3660);
PAINT MONO (1285 3660);
DISPLAY INVISIBLE (1285 3660);
FORCEPROP 1 LASTPIN (1275 3650) BN 3
J 0
(1263 3658);
DISPLAY 0.680851 (1263 3658);
PAINT GREEN (1263 3658);
FORCEPROP 2 LAST CDS_LIB standard
J 0
(1325 3650);
PAINT MONO (1325 3650);
DISPLAY INVISIBLE (1325 3650);
FORCEPROP 1 LAST BODY_TYPE PLUMBING
J 0
(1325 3700);
DISPLAY 0.872340 (1325 3700);
PAINT GREEN (1325 3700);
DISPLAY INVISIBLE (1325 3700);
FORCEPROP 1 LAST HDL_TAP TRUE
J 0
(1650 3525);
DISPLAY 0.872340 (1650 3525);
DISPLAY INVISIBLE (1650 3525);
FORCEPROP 1 LAST PATH I155
J 0
(1323 3650);
DISPLAY 0.872340 (1323 3650);
PAINT GREEN (1323 3650);
DISPLAY INVISIBLE (1323 3650);
FORCEADD TAP..1
(1325 3550);
FORCEPROP 3 LASTPIN (1275 3550) SIG_NAME M_H_CPU1_SA_DQS_DN<2>
J 0
(1285 3560);
DISPLAY 0.659574 (1285 3560);
PAINT MONO (1285 3560);
DISPLAY INVISIBLE (1285 3560);
FORCEPROP 1 LASTPIN (1275 3550) BN 2
J 0
(1263 3558);
DISPLAY 0.680851 (1263 3558);
PAINT GREEN (1263 3558);
FORCEPROP 2 LAST CDS_LIB standard
J 0
(1325 3550);
DISPLAY INVISIBLE (1325 3550);
FORCEPROP 1 LAST BODY_TYPE PLUMBING
J 0
(1325 3600);
DISPLAY 0.872340 (1325 3600);
PAINT GREEN (1325 3600);
DISPLAY INVISIBLE (1325 3600);
FORCEPROP 1 LAST HDL_TAP TRUE
J 0
(1650 3425);
DISPLAY 0.872340 (1650 3425);
DISPLAY INVISIBLE (1650 3425);
FORCEPROP 1 LAST PATH I156
J 0
(1323 3550);
DISPLAY 0.872340 (1323 3550);
PAINT GREEN (1323 3550);
DISPLAY INVISIBLE (1323 3550);
FORCEADD TAP..1
(1150 3700);
FORCEPROP 3 LASTPIN (1100 3700) SIG_NAME M_H_CPU1_SA_DQS_DP<3>
J 0
(1110 3710);
DISPLAY 0.659574 (1110 3710);
PAINT MONO (1110 3710);
DISPLAY INVISIBLE (1110 3710);
FORCEPROP 1 LASTPIN (1100 3700) BN 3
J 0
(1088 3708);
DISPLAY 0.680851 (1088 3708);
PAINT GREEN (1088 3708);
FORCEPROP 2 LAST CDS_LIB standard
J 0
(1150 3700);
PAINT MONO (1150 3700);
DISPLAY INVISIBLE (1150 3700);
FORCEPROP 1 LAST BODY_TYPE PLUMBING
J 0
(1150 3750);
DISPLAY 0.872340 (1150 3750);
PAINT GREEN (1150 3750);
DISPLAY INVISIBLE (1150 3750);
FORCEPROP 1 LAST HDL_TAP TRUE
J 0
(1475 3575);
DISPLAY 0.872340 (1475 3575);
DISPLAY INVISIBLE (1475 3575);
FORCEPROP 1 LAST PATH I157
J 0
(1148 3700);
DISPLAY 0.872340 (1148 3700);
PAINT GREEN (1148 3700);
DISPLAY INVISIBLE (1148 3700);
FORCEADD TAP..1
(1150 3800);
FORCEPROP 3 LASTPIN (1100 3800) SIG_NAME M_H_CPU1_SA_DQS_DP<4>
J 0
(1110 3810);
DISPLAY 0.659574 (1110 3810);
PAINT MONO (1110 3810);
DISPLAY INVISIBLE (1110 3810);
FORCEPROP 1 LASTPIN (1100 3800) BN 4
J 0
(1088 3808);
DISPLAY 0.680851 (1088 3808);
PAINT GREEN (1088 3808);
FORCEPROP 2 LAST CDS_LIB standard
J 0
(1150 3800);
PAINT MONO (1150 3800);
DISPLAY INVISIBLE (1150 3800);
FORCEPROP 1 LAST BODY_TYPE PLUMBING
J 0
(1150 3850);
DISPLAY 0.872340 (1150 3850);
PAINT GREEN (1150 3850);
DISPLAY INVISIBLE (1150 3850);
FORCEPROP 1 LAST HDL_TAP TRUE
J 0
(1475 3675);
DISPLAY 0.872340 (1475 3675);
DISPLAY INVISIBLE (1475 3675);
FORCEPROP 1 LAST PATH I158
J 0
(1148 3800);
DISPLAY 0.872340 (1148 3800);
PAINT GREEN (1148 3800);
DISPLAY INVISIBLE (1148 3800);
FORCEADD TAP..1
(1150 3900);
FORCEPROP 3 LASTPIN (1100 3900) SIG_NAME M_H_CPU1_SA_DQS_DP<5>
J 0
(1110 3910);
DISPLAY 0.659574 (1110 3910);
PAINT MONO (1110 3910);
DISPLAY INVISIBLE (1110 3910);
FORCEPROP 1 LASTPIN (1100 3900) BN 5
J 0
(1088 3908);
DISPLAY 0.680851 (1088 3908);
PAINT GREEN (1088 3908);
FORCEPROP 2 LAST CDS_LIB standard
J 0
(1150 3900);
DISPLAY INVISIBLE (1150 3900);
FORCEPROP 1 LAST BODY_TYPE PLUMBING
J 0
(1150 3950);
DISPLAY 0.872340 (1150 3950);
PAINT GREEN (1150 3950);
DISPLAY INVISIBLE (1150 3950);
FORCEPROP 1 LAST HDL_TAP TRUE
J 0
(1475 3775);
DISPLAY 0.872340 (1475 3775);
DISPLAY INVISIBLE (1475 3775);
FORCEPROP 1 LAST PATH I159
J 0
(1148 3900);
DISPLAY 0.872340 (1148 3900);
PAINT GREEN (1148 3900);
DISPLAY INVISIBLE (1148 3900);
FORCEADD TAP..1
R 2
(-3250 2200);
FORCEPROP 3 LASTPIN (-3200 2200) SIG_NAME M_H_CPU1_SB_CB<2>
J 0
(-3190 2210);
DISPLAY 0.659574 (-3190 2210);
PAINT MONO (-3190 2210);
DISPLAY INVISIBLE (-3190 2210);
FORCEPROP 1 LASTPIN (-3200 2200) BN 2
J 2
(-3188 2208);
DISPLAY 0.680851 (-3188 2208);
PAINT GREEN (-3188 2208);
FORCEPROP 2 LAST CDS_LIB standard
J 0
(-3250 2200);
DISPLAY INVISIBLE (-3250 2200);
FORCEPROP 1 LAST BODY_TYPE PLUMBING
J 2
(-3250 2250);
DISPLAY 0.872340 (-3250 2250);
PAINT GREEN (-3250 2250);
DISPLAY INVISIBLE (-3250 2250);
FORCEPROP 1 LAST HDL_TAP TRUE
J 2
(-3575 2075);
DISPLAY 0.872340 (-3575 2075);
DISPLAY INVISIBLE (-3575 2075);
FORCEPROP 1 LAST PATH I16
J 2
(-3248 2200);
DISPLAY 0.872340 (-3248 2200);
PAINT GREEN (-3248 2200);
DISPLAY INVISIBLE (-3248 2200);
FORCEADD TAP..1
(1325 3750);
FORCEPROP 3 LASTPIN (1275 3750) SIG_NAME M_H_CPU1_SA_DQS_DN<4>
J 0
(1285 3760);
DISPLAY 0.659574 (1285 3760);
PAINT MONO (1285 3760);
DISPLAY INVISIBLE (1285 3760);
FORCEPROP 1 LASTPIN (1275 3750) BN 4
J 0
(1263 3758);
DISPLAY 0.680851 (1263 3758);
PAINT GREEN (1263 3758);
FORCEPROP 2 LAST CDS_LIB standard
J 0
(1325 3750);
PAINT MONO (1325 3750);
DISPLAY INVISIBLE (1325 3750);
FORCEPROP 1 LAST BODY_TYPE PLUMBING
J 0
(1325 3800);
DISPLAY 0.872340 (1325 3800);
PAINT GREEN (1325 3800);
DISPLAY INVISIBLE (1325 3800);
FORCEPROP 1 LAST HDL_TAP TRUE
J 0
(1650 3625);
DISPLAY 0.872340 (1650 3625);
DISPLAY INVISIBLE (1650 3625);
FORCEPROP 1 LAST PATH I160
J 0
(1323 3750);
DISPLAY 0.872340 (1323 3750);
PAINT GREEN (1323 3750);
DISPLAY INVISIBLE (1323 3750);
FORCEADD TAP..1
(1325 3850);
FORCEPROP 3 LASTPIN (1275 3850) SIG_NAME M_H_CPU1_SA_DQS_DN<5>
J 0
(1285 3860);
DISPLAY 0.659574 (1285 3860);
PAINT MONO (1285 3860);
DISPLAY INVISIBLE (1285 3860);
FORCEPROP 1 LASTPIN (1275 3850) BN 5
J 0
(1263 3858);
DISPLAY 0.680851 (1263 3858);
PAINT GREEN (1263 3858);
FORCEPROP 2 LAST CDS_LIB standard
J 0
(1325 3850);
DISPLAY INVISIBLE (1325 3850);
FORCEPROP 1 LAST BODY_TYPE PLUMBING
J 0
(1325 3900);
DISPLAY 0.872340 (1325 3900);
PAINT GREEN (1325 3900);
DISPLAY INVISIBLE (1325 3900);
FORCEPROP 1 LAST HDL_TAP TRUE
J 0
(1650 3725);
DISPLAY 0.872340 (1650 3725);
DISPLAY INVISIBLE (1650 3725);
FORCEPROP 1 LAST PATH I161
J 0
(1323 3850);
DISPLAY 0.872340 (1323 3850);
PAINT GREEN (1323 3850);
DISPLAY INVISIBLE (1323 3850);
FORCEADD TAP..1
(1150 4000);
FORCEPROP 3 LASTPIN (1100 4000) SIG_NAME M_H_CPU1_SA_DQS_DP<6>
J 0
(1110 4010);
DISPLAY 0.659574 (1110 4010);
PAINT MONO (1110 4010);
DISPLAY INVISIBLE (1110 4010);
FORCEPROP 1 LASTPIN (1100 4000) BN 6
J 0
(1088 4008);
DISPLAY 0.680851 (1088 4008);
PAINT GREEN (1088 4008);
FORCEPROP 2 LAST CDS_LIB standard
J 0
(1150 4000);
DISPLAY INVISIBLE (1150 4000);
FORCEPROP 1 LAST BODY_TYPE PLUMBING
J 0
(1150 4050);
DISPLAY 0.872340 (1150 4050);
PAINT GREEN (1150 4050);
DISPLAY INVISIBLE (1150 4050);
FORCEPROP 1 LAST HDL_TAP TRUE
J 0
(1475 3875);
DISPLAY 0.872340 (1475 3875);
DISPLAY INVISIBLE (1475 3875);
FORCEPROP 1 LAST PATH I162
J 0
(1148 4000);
DISPLAY 0.872340 (1148 4000);
PAINT GREEN (1148 4000);
DISPLAY INVISIBLE (1148 4000);
FORCEADD TAP..1
(1150 4100);
FORCEPROP 3 LASTPIN (1100 4100) SIG_NAME M_H_CPU1_SA_DQS_DP<7>
J 0
(1110 4110);
DISPLAY 0.659574 (1110 4110);
PAINT MONO (1110 4110);
DISPLAY INVISIBLE (1110 4110);
FORCEPROP 1 LASTPIN (1100 4100) BN 7
J 0
(1088 4108);
DISPLAY 0.680851 (1088 4108);
PAINT GREEN (1088 4108);
FORCEPROP 2 LAST CDS_LIB standard
J 0
(1150 4100);
DISPLAY INVISIBLE (1150 4100);
FORCEPROP 1 LAST BODY_TYPE PLUMBING
J 0
(1150 4150);
DISPLAY 0.872340 (1150 4150);
PAINT GREEN (1150 4150);
DISPLAY INVISIBLE (1150 4150);
FORCEPROP 1 LAST HDL_TAP TRUE
J 0
(1475 3975);
DISPLAY 0.872340 (1475 3975);
DISPLAY INVISIBLE (1475 3975);
FORCEPROP 1 LAST PATH I163
J 0
(1148 4100);
DISPLAY 0.872340 (1148 4100);
PAINT GREEN (1148 4100);
DISPLAY INVISIBLE (1148 4100);
FORCEADD TAP..1
(1325 3950);
FORCEPROP 3 LASTPIN (1275 3950) SIG_NAME M_H_CPU1_SA_DQS_DN<6>
J 0
(1285 3960);
DISPLAY 0.659574 (1285 3960);
PAINT MONO (1285 3960);
DISPLAY INVISIBLE (1285 3960);
FORCEPROP 1 LASTPIN (1275 3950) BN 6
J 0
(1263 3958);
DISPLAY 0.680851 (1263 3958);
PAINT GREEN (1263 3958);
FORCEPROP 2 LAST CDS_LIB standard
J 0
(1325 3950);
DISPLAY INVISIBLE (1325 3950);
FORCEPROP 1 LAST BODY_TYPE PLUMBING
J 0
(1325 4000);
DISPLAY 0.872340 (1325 4000);
PAINT GREEN (1325 4000);
DISPLAY INVISIBLE (1325 4000);
FORCEPROP 1 LAST HDL_TAP TRUE
J 0
(1650 3825);
DISPLAY 0.872340 (1650 3825);
DISPLAY INVISIBLE (1650 3825);
FORCEPROP 1 LAST PATH I164
J 0
(1323 3950);
DISPLAY 0.872340 (1323 3950);
PAINT GREEN (1323 3950);
DISPLAY INVISIBLE (1323 3950);
FORCEADD TAP..1
(1325 4150);
FORCEPROP 3 LASTPIN (1275 4150) SIG_NAME M_H_CPU1_SA_DQS_DN<8>
J 0
(1285 4160);
DISPLAY 0.659574 (1285 4160);
PAINT MONO (1285 4160);
DISPLAY INVISIBLE (1285 4160);
FORCEPROP 1 LASTPIN (1275 4150) BN 8
J 0
(1263 4158);
DISPLAY 0.680851 (1263 4158);
PAINT GREEN (1263 4158);
FORCEPROP 2 LAST CDS_LIB standard
J 0
(1325 4150);
DISPLAY INVISIBLE (1325 4150);
FORCEPROP 1 LAST BODY_TYPE PLUMBING
J 0
(1325 4200);
DISPLAY 0.872340 (1325 4200);
PAINT GREEN (1325 4200);
DISPLAY INVISIBLE (1325 4200);
FORCEPROP 1 LAST HDL_TAP TRUE
J 0
(1650 4025);
DISPLAY 0.872340 (1650 4025);
DISPLAY INVISIBLE (1650 4025);
FORCEPROP 1 LAST PATH I165
J 0
(1323 4150);
DISPLAY 0.872340 (1323 4150);
PAINT GREEN (1323 4150);
DISPLAY INVISIBLE (1323 4150);
FORCEADD TAP..1
(1325 4050);
FORCEPROP 3 LASTPIN (1275 4050) SIG_NAME M_H_CPU1_SA_DQS_DN<7>
J 0
(1285 4060);
DISPLAY 0.659574 (1285 4060);
PAINT MONO (1285 4060);
DISPLAY INVISIBLE (1285 4060);
FORCEPROP 1 LASTPIN (1275 4050) BN 7
J 0
(1263 4058);
DISPLAY 0.680851 (1263 4058);
PAINT GREEN (1263 4058);
FORCEPROP 2 LAST CDS_LIB standard
J 0
(1325 4050);
DISPLAY INVISIBLE (1325 4050);
FORCEPROP 1 LAST BODY_TYPE PLUMBING
J 0
(1325 4100);
DISPLAY 0.872340 (1325 4100);
PAINT GREEN (1325 4100);
DISPLAY INVISIBLE (1325 4100);
FORCEPROP 1 LAST HDL_TAP TRUE
J 0
(1650 3925);
DISPLAY 0.872340 (1650 3925);
DISPLAY INVISIBLE (1650 3925);
FORCEPROP 1 LAST PATH I166
J 0
(1323 4050);
DISPLAY 0.872340 (1323 4050);
PAINT GREEN (1323 4050);
DISPLAY INVISIBLE (1323 4050);
FORCEADD TAP..1
(1150 4200);
FORCEPROP 3 LASTPIN (1100 4200) SIG_NAME M_H_CPU1_SA_DQS_DP<8>
J 0
(1110 4210);
DISPLAY 0.659574 (1110 4210);
PAINT MONO (1110 4210);
DISPLAY INVISIBLE (1110 4210);
FORCEPROP 1 LASTPIN (1100 4200) BN 8
J 0
(1088 4208);
DISPLAY 0.680851 (1088 4208);
PAINT GREEN (1088 4208);
FORCEPROP 2 LAST CDS_LIB standard
J 0
(1150 4200);
DISPLAY INVISIBLE (1150 4200);
FORCEPROP 1 LAST BODY_TYPE PLUMBING
J 0
(1150 4250);
DISPLAY 0.872340 (1150 4250);
PAINT GREEN (1150 4250);
DISPLAY INVISIBLE (1150 4250);
FORCEPROP 1 LAST HDL_TAP TRUE
J 0
(1475 4075);
DISPLAY 0.872340 (1475 4075);
DISPLAY INVISIBLE (1475 4075);
FORCEPROP 1 LAST PATH I167
J 0
(1148 4200);
DISPLAY 0.872340 (1148 4200);
PAINT GREEN (1148 4200);
DISPLAY INVISIBLE (1148 4200);
FORCEADD TAP..1
(1150 4300);
FORCEPROP 3 LASTPIN (1100 4300) SIG_NAME M_H_CPU1_SA_DQS_DP<9>
J 0
(1110 4310);
DISPLAY 0.659574 (1110 4310);
PAINT MONO (1110 4310);
DISPLAY INVISIBLE (1110 4310);
FORCEPROP 1 LASTPIN (1100 4300) BN 9
J 0
(1088 4308);
DISPLAY 0.680851 (1088 4308);
PAINT GREEN (1088 4308);
FORCEPROP 2 LAST CDS_LIB standard
J 0
(1150 4300);
DISPLAY INVISIBLE (1150 4300);
FORCEPROP 1 LAST BODY_TYPE PLUMBING
J 0
(1150 4350);
DISPLAY 0.872340 (1150 4350);
PAINT GREEN (1150 4350);
DISPLAY INVISIBLE (1150 4350);
FORCEPROP 1 LAST HDL_TAP TRUE
J 0
(1475 4175);
DISPLAY 0.872340 (1475 4175);
DISPLAY INVISIBLE (1475 4175);
FORCEPROP 1 LAST PATH I168
J 0
(1148 4300);
DISPLAY 0.872340 (1148 4300);
PAINT GREEN (1148 4300);
DISPLAY INVISIBLE (1148 4300);
FORCEADD TAP..1
(1325 4250);
FORCEPROP 3 LASTPIN (1275 4250) SIG_NAME M_H_CPU1_SA_DQS_DN<9>
J 0
(1285 4260);
DISPLAY 0.659574 (1285 4260);
PAINT MONO (1285 4260);
DISPLAY INVISIBLE (1285 4260);
FORCEPROP 1 LASTPIN (1275 4250) BN 9
J 0
(1263 4258);
DISPLAY 0.680851 (1263 4258);
PAINT GREEN (1263 4258);
FORCEPROP 2 LAST CDS_LIB standard
J 0
(1325 4250);
DISPLAY INVISIBLE (1325 4250);
FORCEPROP 1 LAST BODY_TYPE PLUMBING
J 0
(1325 4300);
DISPLAY 0.872340 (1325 4300);
PAINT GREEN (1325 4300);
DISPLAY INVISIBLE (1325 4300);
FORCEPROP 1 LAST HDL_TAP TRUE
J 0
(1650 4125);
DISPLAY 0.872340 (1650 4125);
DISPLAY INVISIBLE (1650 4125);
FORCEPROP 1 LAST PATH I169
J 0
(1323 4250);
DISPLAY 0.872340 (1323 4250);
PAINT GREEN (1323 4250);
DISPLAY INVISIBLE (1323 4250);
FORCEADD TAP..1
R 2
(-3250 2250);
FORCEPROP 3 LASTPIN (-3200 2250) SIG_NAME M_H_CPU1_SB_CB<3>
J 0
(-3190 2260);
DISPLAY 0.659574 (-3190 2260);
PAINT MONO (-3190 2260);
DISPLAY INVISIBLE (-3190 2260);
FORCEPROP 1 LASTPIN (-3200 2250) BN 3
J 2
(-3188 2258);
DISPLAY 0.680851 (-3188 2258);
PAINT GREEN (-3188 2258);
FORCEPROP 2 LAST CDS_LIB standard
J 0
(-3250 2250);
DISPLAY INVISIBLE (-3250 2250);
FORCEPROP 1 LAST BODY_TYPE PLUMBING
J 2
(-3250 2300);
DISPLAY 0.872340 (-3250 2300);
PAINT GREEN (-3250 2300);
DISPLAY INVISIBLE (-3250 2300);
FORCEPROP 1 LAST HDL_TAP TRUE
J 2
(-3575 2125);
DISPLAY 0.872340 (-3575 2125);
DISPLAY INVISIBLE (-3575 2125);
FORCEPROP 1 LAST PATH I17
J 2
(-3248 2250);
DISPLAY 0.872340 (-3248 2250);
PAINT GREEN (-3248 2250);
DISPLAY INVISIBLE (-3248 2250);
FORCEADD UNIVERSAL_GND..1
(2825 600);
FORCEPROP 3 LASTPIN (2825 650) SIG_NAME GND\g
J 0
(2835 660);
DISPLAY 0.659574 (2835 660);
PAINT MONO (2835 660);
DISPLAY INVISIBLE (2835 660);
FORCEPROP 1 LAST PATH I170
J 0
(2900 600);
DISPLAY 0.872340 (2900 600);
PAINT AQUA (2900 600);
DISPLAY INVISIBLE (2900 600);
FORCEPROP 1 LAST HDL_POWER GND
J 1
(2850 525);
DISPLAY 0.872340 (2850 525);
PAINT GREEN (2850 525);
DISPLAY INVISIBLE (2850 525);
FORCEPROP 2 LAST CDS_LIB logical_power
J 0
(2825 600);
PAINT MONO (2825 600);
DISPLAY INVISIBLE (2825 600);
FORCEADD OFFPAGE..2
(2275 3275);
FORCEPROP 2 LAST $XR1 113 
J 0
(2554 3275);
DISPLAY 0.638298 (2554 3275);
PAINT MONO (2554 3275);
FORCEPROP 2 LAST $XR0 58 
J 0
(2464 3275);
DISPLAY 0.638298 (2464 3275);
PAINT MONO (2464 3275);
FORCEPROP 2 LAST CDS_LIB standard
J 0
(2275 3275);
PAINT MONO (2275 3275);
DISPLAY INVISIBLE (2275 3275);
FORCEPROP 1 LAST OFFPAGE TRUE
J 0
(2600 3150);
DISPLAY 1.170213 (2600 3150);
PAINT GREEN (2600 3150);
DISPLAY INVISIBLE (2600 3150);
FORCEPROP 1 LAST COMMENT_BODY TRUE
J 0
(2230 3180);
DISPLAY 1.170213 (2230 3180);
PAINT GREEN (2230 3180);
DISPLAY INVISIBLE (2230 3180);
FORCEPROP 2 LAST PATH I172
J 0
(2450 3350);
DISPLAY 1.021277 (2450 3350);
DISPLAY INVISIBLE (2450 3350);
FORCEADD OFFPAGE..2
(2275 3225);
FORCEPROP 2 LAST $XR1 113 
J 0
(2554 3225);
DISPLAY 0.638298 (2554 3225);
PAINT MONO (2554 3225);
FORCEPROP 2 LAST $XR0 58 
J 0
(2464 3225);
DISPLAY 0.638298 (2464 3225);
PAINT MONO (2464 3225);
FORCEPROP 2 LAST CDS_LIB standard
J 0
(2275 3225);
PAINT MONO (2275 3225);
DISPLAY INVISIBLE (2275 3225);
FORCEPROP 1 LAST OFFPAGE TRUE
J 0
(2600 3100);
DISPLAY 1.170213 (2600 3100);
PAINT GREEN (2600 3100);
DISPLAY INVISIBLE (2600 3100);
FORCEPROP 1 LAST COMMENT_BODY TRUE
J 0
(2230 3130);
DISPLAY 1.170213 (2230 3130);
PAINT GREEN (2230 3130);
DISPLAY INVISIBLE (2230 3130);
FORCEPROP 2 LAST PATH I173
J 0
(2450 3300);
DISPLAY 1.021277 (2450 3300);
DISPLAY INVISIBLE (2450 3300);
FORCEADD OFFPAGE..2
(2275 4275);
FORCEPROP 2 LAST $XR1 113 
J 0
(2554 4275);
DISPLAY 0.638298 (2554 4275);
PAINT MONO (2554 4275);
FORCEPROP 2 LAST $XR0 58 
J 0
(2464 4275);
DISPLAY 0.638298 (2464 4275);
PAINT MONO (2464 4275);
FORCEPROP 2 LAST CDS_LIB standard
J 0
(2275 4275);
PAINT MONO (2275 4275);
DISPLAY INVISIBLE (2275 4275);
FORCEPROP 1 LAST OFFPAGE TRUE
J 0
(2600 4150);
DISPLAY 1.170213 (2600 4150);
PAINT GREEN (2600 4150);
DISPLAY INVISIBLE (2600 4150);
FORCEPROP 1 LAST COMMENT_BODY TRUE
J 0
(2230 4180);
DISPLAY 1.170213 (2230 4180);
PAINT GREEN (2230 4180);
DISPLAY INVISIBLE (2230 4180);
FORCEPROP 2 LAST PATH I174
J 0
(2450 4350);
DISPLAY 1.021277 (2450 4350);
DISPLAY INVISIBLE (2450 4350);
FORCEADD OFFPAGE..2
(2275 4325);
FORCEPROP 2 LAST $XR1 113 
J 0
(2554 4325);
DISPLAY 0.638298 (2554 4325);
PAINT MONO (2554 4325);
FORCEPROP 2 LAST $XR0 58 
J 0
(2464 4325);
DISPLAY 0.638298 (2464 4325);
PAINT MONO (2464 4325);
FORCEPROP 2 LAST CDS_LIB standard
J 0
(2275 4325);
PAINT MONO (2275 4325);
DISPLAY INVISIBLE (2275 4325);
FORCEPROP 1 LAST OFFPAGE TRUE
J 0
(2600 4200);
DISPLAY 1.170213 (2600 4200);
PAINT GREEN (2600 4200);
DISPLAY INVISIBLE (2600 4200);
FORCEPROP 1 LAST COMMENT_BODY TRUE
J 0
(2230 4230);
DISPLAY 1.170213 (2230 4230);
PAINT GREEN (2230 4230);
DISPLAY INVISIBLE (2230 4230);
FORCEPROP 2 LAST PATH I175
J 0
(2450 4400);
DISPLAY 1.021277 (2450 4400);
DISPLAY INVISIBLE (2450 4400);
FORCEADD VCC_CORE..1
(2825 4850);
FORCEPROP 3 LASTPIN (2825 4800) SIG_NAME P12V_S3_AUX_CPU1_NVDIMM\g
J 0
(2835 4810);
DISPLAY 0.659574 (2835 4810);
PAINT MONO (2835 4810);
DISPLAY INVISIBLE (2835 4810);
FORCEPROP 1 LAST HDL_POWER P12V_S3_AUX_CPU1_NVDIMM
J 1
(2825 4900);
DISPLAY 1.148936 (2825 4900);
PAINT GREEN (2825 4900);
FORCEPROP 2 LAST CDS_LIB logical_power
J 0
(2825 4850);
PAINT MONO (2825 4850);
DISPLAY INVISIBLE (2825 4850);
FORCEPROP 1 LAST PATH I176
J 0
(2875 4875);
DISPLAY 0.872340 (2875 4875);
PAINT AQUA (2875 4875);
DISPLAY INVISIBLE (2875 4875);
FORCEADD UNIVERSAL_GND..1
(4525 600);
FORCEPROP 3 LASTPIN (4525 650) SIG_NAME GND\g
J 0
(4535 660);
DISPLAY 0.659574 (4535 660);
PAINT MONO (4535 660);
DISPLAY INVISIBLE (4535 660);
FORCEPROP 1 LAST PATH I177
J 0
(4600 600);
DISPLAY 0.872340 (4600 600);
PAINT AQUA (4600 600);
DISPLAY INVISIBLE (4600 600);
FORCEPROP 1 LAST HDL_POWER GND
J 1
(4550 525);
DISPLAY 0.872340 (4550 525);
PAINT GREEN (4550 525);
DISPLAY INVISIBLE (4550 525);
FORCEPROP 2 LAST CDS_LIB logical_power
J 0
(4525 600);
PAINT MONO (4525 600);
DISPLAY INVISIBLE (4525 600);
FORCEADD SCONN288_ADR50017P130CC..3
(3675 2675);
FORCEPROP 1 LAST PART_NUMBER DFHST8FS461
J 0
(3220 4599);
DISPLAY 0.723404 (3220 4599);
PAINT GREEN (3220 4599);
DISPLAY INVISIBLE (3220 4599);
FORCEPROP 1 LAST MATERIAL IO
J 0
(3220 4472);
DISPLAY 0.723404 (3220 4472);
PAINT GREEN (3220 4472);
FORCEPROP 2 LAST VALUE SCONN288_ADR50017-P130CC
J 0
(3225 4700);
DISPLAY 1.021277 (3225 4700);
FORCEPROP 2 LAST PART_TYPE SMLF
J 0
(3225 4775);
DISPLAY 1.021277 (3225 4775);
FORCEPROP 1 LAST $LOCATION J31
J 0
(3225 4675);
DISPLAY 0.723404 (3225 4675);
PAINT GREEN (3225 4675);
FORCEPROP 0 LASTPIN (4275 1050) $PN G1
J 0
(4285 1060);
DISPLAY 0.680851 (4285 1060);
PAINT MONO (4285 1060);
FORCEPROP 0 LASTPIN (4275 1000) $PN G2
J 0
(4285 1010);
DISPLAY 0.680851 (4285 1010);
PAINT MONO (4285 1010);
FORCEPROP 0 LASTPIN (4275 950) $PN G3
J 0
(4285 960);
DISPLAY 0.680851 (4285 960);
PAINT MONO (4285 960);
FORCEPROP 0 LASTPIN (3075 4200) $PN 1
J 2
(3065 4210);
DISPLAY 0.680851 (3065 4210);
PAINT MONO (3065 4210);
FORCEPROP 0 LASTPIN (3075 4250) $PN 145
J 2
(3065 4260);
DISPLAY 0.680851 (3065 4260);
PAINT MONO (3065 4260);
FORCEPROP 0 LASTPIN (3075 4300) $PN 146
J 2
(3065 4310);
DISPLAY 0.680851 (3065 4310);
PAINT MONO (3065 4310);
FORCEPROP 0 LASTPIN (4275 1150) $PN 6
J 0
(4285 1160);
DISPLAY 0.680851 (4285 1160);
PAINT MONO (4285 1160);
FORCEPROP 0 LASTPIN (4275 1200) $PN 8
J 0
(4285 1210);
DISPLAY 0.680851 (4285 1210);
PAINT MONO (4285 1210);
FORCEPROP 0 LASTPIN (4275 1250) $PN 10
J 0
(4285 1260);
DISPLAY 0.680851 (4285 1260);
PAINT MONO (4285 1260);
FORCEPROP 0 LASTPIN (4275 1300) $PN 13
J 0
(4285 1310);
DISPLAY 0.680851 (4285 1310);
PAINT MONO (4285 1310);
FORCEPROP 0 LASTPIN (4275 1350) $PN 15
J 0
(4285 1360);
DISPLAY 0.680851 (4285 1360);
PAINT MONO (4285 1360);
FORCEPROP 0 LASTPIN (4275 1400) $PN 17
J 0
(4285 1410);
DISPLAY 0.680851 (4285 1410);
PAINT MONO (4285 1410);
FORCEPROP 0 LASTPIN (4275 1450) $PN 19
J 0
(4285 1460);
DISPLAY 0.680851 (4285 1460);
PAINT MONO (4285 1460);
FORCEPROP 0 LASTPIN (4275 1500) $PN 21
J 0
(4285 1510);
DISPLAY 0.680851 (4285 1510);
PAINT MONO (4285 1510);
FORCEPROP 0 LASTPIN (4275 1550) $PN 24
J 0
(4285 1560);
DISPLAY 0.680851 (4285 1560);
PAINT MONO (4285 1560);
FORCEPROP 0 LASTPIN (4275 1600) $PN 26
J 0
(4285 1610);
DISPLAY 0.680851 (4285 1610);
PAINT MONO (4285 1610);
FORCEPROP 0 LASTPIN (4275 1650) $PN 28
J 0
(4285 1660);
DISPLAY 0.680851 (4285 1660);
PAINT MONO (4285 1660);
FORCEPROP 0 LASTPIN (4275 1700) $PN 30
J 0
(4285 1710);
DISPLAY 0.680851 (4285 1710);
PAINT MONO (4285 1710);
FORCEPROP 0 LASTPIN (4275 1750) $PN 32
J 0
(4285 1760);
DISPLAY 0.680851 (4285 1760);
PAINT MONO (4285 1760);
FORCEPROP 0 LASTPIN (4275 1800) $PN 35
J 0
(4285 1810);
DISPLAY 0.680851 (4285 1810);
PAINT MONO (4285 1810);
FORCEPROP 0 LASTPIN (4275 1850) $PN 37
J 0
(4285 1860);
DISPLAY 0.680851 (4285 1860);
PAINT MONO (4285 1860);
FORCEPROP 0 LASTPIN (4275 1900) $PN 39
J 0
(4285 1910);
DISPLAY 0.680851 (4285 1910);
PAINT MONO (4285 1910);
FORCEPROP 0 LASTPIN (4275 1950) $PN 41
J 0
(4285 1960);
DISPLAY 0.680851 (4285 1960);
PAINT MONO (4285 1960);
FORCEPROP 0 LASTPIN (4275 2000) $PN 43
J 0
(4285 2010);
DISPLAY 0.680851 (4285 2010);
PAINT MONO (4285 2010);
FORCEPROP 0 LASTPIN (4275 2050) $PN 46
J 0
(4285 2060);
DISPLAY 0.680851 (4285 2060);
PAINT MONO (4285 2060);
FORCEPROP 0 LASTPIN (4275 2100) $PN 48
J 0
(4285 2110);
DISPLAY 0.680851 (4285 2110);
PAINT MONO (4285 2110);
FORCEPROP 0 LASTPIN (4275 2150) $PN 50
J 0
(4285 2160);
DISPLAY 0.680851 (4285 2160);
PAINT MONO (4285 2160);
FORCEPROP 0 LASTPIN (4275 2200) $PN 52
J 0
(4285 2210);
DISPLAY 0.680851 (4285 2210);
PAINT MONO (4285 2210);
FORCEPROP 0 LASTPIN (4275 2250) $PN 54
J 0
(4285 2260);
DISPLAY 0.680851 (4285 2260);
PAINT MONO (4285 2260);
FORCEPROP 0 LASTPIN (4275 2300) $PN 57
J 0
(4285 2310);
DISPLAY 0.680851 (4285 2310);
PAINT MONO (4285 2310);
FORCEPROP 0 LASTPIN (4275 2350) $PN 59
J 0
(4285 2360);
DISPLAY 0.680851 (4285 2360);
PAINT MONO (4285 2360);
FORCEPROP 0 LASTPIN (4275 2400) $PN 61
J 0
(4285 2410);
DISPLAY 0.680851 (4285 2410);
PAINT MONO (4285 2410);
FORCEPROP 0 LASTPIN (4275 2450) $PN 63
J 0
(4285 2460);
DISPLAY 0.680851 (4285 2460);
PAINT MONO (4285 2460);
FORCEPROP 0 LASTPIN (4275 2500) $PN 65
J 0
(4285 2510);
DISPLAY 0.680851 (4285 2510);
PAINT MONO (4285 2510);
FORCEPROP 0 LASTPIN (4275 2550) $PN 67
J 0
(4285 2560);
DISPLAY 0.680851 (4285 2560);
PAINT MONO (4285 2560);
FORCEPROP 0 LASTPIN (4275 2600) $PN 69
J 0
(4285 2610);
DISPLAY 0.680851 (4285 2610);
PAINT MONO (4285 2610);
FORCEPROP 0 LASTPIN (4275 2650) $PN 71
J 0
(4285 2660);
DISPLAY 0.680851 (4285 2660);
PAINT MONO (4285 2660);
FORCEPROP 0 LASTPIN (4275 2700) $PN 73
J 0
(4285 2710);
DISPLAY 0.680851 (4285 2710);
PAINT MONO (4285 2710);
FORCEPROP 0 LASTPIN (4275 2750) $PN 75
J 0
(4285 2760);
DISPLAY 0.680851 (4285 2760);
PAINT MONO (4285 2760);
FORCEPROP 0 LASTPIN (4275 2800) $PN 77
J 0
(4285 2810);
DISPLAY 0.680851 (4285 2810);
PAINT MONO (4285 2810);
FORCEPROP 0 LASTPIN (4275 2850) $PN 79
J 0
(4285 2860);
DISPLAY 0.680851 (4285 2860);
PAINT MONO (4285 2860);
FORCEPROP 0 LASTPIN (4275 2900) $PN 81
J 0
(4285 2910);
DISPLAY 0.680851 (4285 2910);
PAINT MONO (4285 2910);
FORCEPROP 0 LASTPIN (4275 2950) $PN 83
J 0
(4285 2960);
DISPLAY 0.680851 (4285 2960);
PAINT MONO (4285 2960);
FORCEPROP 0 LASTPIN (4275 3000) $PN 85
J 0
(4285 3010);
DISPLAY 0.680851 (4285 3010);
PAINT MONO (4285 3010);
FORCEPROP 0 LASTPIN (4275 3050) $PN 88
J 0
(4285 3060);
DISPLAY 0.680851 (4285 3060);
PAINT MONO (4285 3060);
FORCEPROP 0 LASTPIN (4275 3100) $PN 90
J 0
(4285 3110);
DISPLAY 0.680851 (4285 3110);
PAINT MONO (4285 3110);
FORCEPROP 0 LASTPIN (4275 3150) $PN 92
J 0
(4285 3160);
DISPLAY 0.680851 (4285 3160);
PAINT MONO (4285 3160);
FORCEPROP 0 LASTPIN (4275 3200) $PN 95
J 0
(4285 3210);
DISPLAY 0.680851 (4285 3210);
PAINT MONO (4285 3210);
FORCEPROP 0 LASTPIN (4275 3250) $PN 97
J 0
(4285 3260);
DISPLAY 0.680851 (4285 3260);
PAINT MONO (4285 3260);
FORCEPROP 0 LASTPIN (4275 3300) $PN 99
J 0
(4285 3310);
DISPLAY 0.680851 (4285 3310);
PAINT MONO (4285 3310);
FORCEPROP 0 LASTPIN (4275 3350) $PN 101
J 0
(4285 3360);
DISPLAY 0.680851 (4285 3360);
PAINT MONO (4285 3360);
FORCEPROP 0 LASTPIN (4275 3400) $PN 103
J 0
(4285 3410);
DISPLAY 0.680851 (4285 3410);
PAINT MONO (4285 3410);
FORCEPROP 0 LASTPIN (4275 3450) $PN 106
J 0
(4285 3460);
DISPLAY 0.680851 (4285 3460);
PAINT MONO (4285 3460);
FORCEPROP 0 LASTPIN (4275 3500) $PN 108
J 0
(4285 3510);
DISPLAY 0.680851 (4285 3510);
PAINT MONO (4285 3510);
FORCEPROP 0 LASTPIN (4275 3550) $PN 110
J 0
(4285 3560);
DISPLAY 0.680851 (4285 3560);
PAINT MONO (4285 3560);
FORCEPROP 0 LASTPIN (4275 3600) $PN 112
J 0
(4285 3610);
DISPLAY 0.680851 (4285 3610);
PAINT MONO (4285 3610);
FORCEPROP 0 LASTPIN (4275 3650) $PN 114
J 0
(4285 3660);
DISPLAY 0.680851 (4285 3660);
PAINT MONO (4285 3660);
FORCEPROP 0 LASTPIN (4275 3700) $PN 117
J 0
(4285 3710);
DISPLAY 0.680851 (4285 3710);
PAINT MONO (4285 3710);
FORCEPROP 0 LASTPIN (4275 3750) $PN 119
J 0
(4285 3760);
DISPLAY 0.680851 (4285 3760);
PAINT MONO (4285 3760);
FORCEPROP 0 LASTPIN (4275 3800) $PN 121
J 0
(4285 3810);
DISPLAY 0.680851 (4285 3810);
PAINT MONO (4285 3810);
FORCEPROP 0 LASTPIN (4275 3850) $PN 123
J 0
(4285 3860);
DISPLAY 0.680851 (4285 3860);
PAINT MONO (4285 3860);
FORCEPROP 0 LASTPIN (4275 3900) $PN 125
J 0
(4285 3910);
DISPLAY 0.680851 (4285 3910);
PAINT MONO (4285 3910);
FORCEPROP 0 LASTPIN (4275 3950) $PN 128
J 0
(4285 3960);
DISPLAY 0.680851 (4285 3960);
PAINT MONO (4285 3960);
FORCEPROP 0 LASTPIN (4275 4000) $PN 130
J 0
(4285 4010);
DISPLAY 0.680851 (4285 4010);
PAINT MONO (4285 4010);
FORCEPROP 0 LASTPIN (4275 4050) $PN 132
J 0
(4285 4060);
DISPLAY 0.680851 (4285 4060);
PAINT MONO (4285 4060);
FORCEPROP 0 LASTPIN (4275 4100) $PN 134
J 0
(4285 4110);
DISPLAY 0.680851 (4285 4110);
PAINT MONO (4285 4110);
FORCEPROP 0 LASTPIN (4275 4150) $PN 136
J 0
(4285 4160);
DISPLAY 0.680851 (4285 4160);
PAINT MONO (4285 4160);
FORCEPROP 0 LASTPIN (4275 4200) $PN 139
J 0
(4285 4210);
DISPLAY 0.680851 (4285 4210);
PAINT MONO (4285 4210);
FORCEPROP 0 LASTPIN (4275 4250) $PN 141
J 0
(4285 4260);
DISPLAY 0.680851 (4285 4260);
PAINT MONO (4285 4260);
FORCEPROP 0 LASTPIN (4275 4300) $PN 143
J 0
(4285 4310);
DISPLAY 0.680851 (4285 4310);
PAINT MONO (4285 4310);
FORCEPROP 0 LASTPIN (3075 1050) $PN 151
J 2
(3065 1060);
DISPLAY 0.680851 (3065 1060);
PAINT MONO (3065 1060);
FORCEPROP 0 LASTPIN (3075 1100) $PN 153
J 2
(3065 1110);
DISPLAY 0.680851 (3065 1110);
PAINT MONO (3065 1110);
FORCEPROP 0 LASTPIN (3075 1150) $PN 155
J 2
(3065 1160);
DISPLAY 0.680851 (3065 1160);
PAINT MONO (3065 1160);
FORCEPROP 0 LASTPIN (3075 1200) $PN 158
J 2
(3065 1210);
DISPLAY 0.680851 (3065 1210);
PAINT MONO (3065 1210);
FORCEPROP 0 LASTPIN (3075 1250) $PN 160
J 2
(3065 1260);
DISPLAY 0.680851 (3065 1260);
PAINT MONO (3065 1260);
FORCEPROP 0 LASTPIN (3075 1300) $PN 162
J 2
(3065 1310);
DISPLAY 0.680851 (3065 1310);
PAINT MONO (3065 1310);
FORCEPROP 0 LASTPIN (3075 1350) $PN 164
J 2
(3065 1360);
DISPLAY 0.680851 (3065 1360);
PAINT MONO (3065 1360);
FORCEPROP 0 LASTPIN (3075 1400) $PN 166
J 2
(3065 1410);
DISPLAY 0.680851 (3065 1410);
PAINT MONO (3065 1410);
FORCEPROP 0 LASTPIN (3075 1450) $PN 169
J 2
(3065 1460);
DISPLAY 0.680851 (3065 1460);
PAINT MONO (3065 1460);
FORCEPROP 0 LASTPIN (3075 1500) $PN 171
J 2
(3065 1510);
DISPLAY 0.680851 (3065 1510);
PAINT MONO (3065 1510);
FORCEPROP 0 LASTPIN (3075 1550) $PN 173
J 2
(3065 1560);
DISPLAY 0.680851 (3065 1560);
PAINT MONO (3065 1560);
FORCEPROP 0 LASTPIN (3075 1600) $PN 175
J 2
(3065 1610);
DISPLAY 0.680851 (3065 1610);
PAINT MONO (3065 1610);
FORCEPROP 0 LASTPIN (3075 1650) $PN 177
J 2
(3065 1660);
DISPLAY 0.680851 (3065 1660);
PAINT MONO (3065 1660);
FORCEPROP 0 LASTPIN (3075 1700) $PN 180
J 2
(3065 1710);
DISPLAY 0.680851 (3065 1710);
PAINT MONO (3065 1710);
FORCEPROP 0 LASTPIN (3075 1750) $PN 182
J 2
(3065 1760);
DISPLAY 0.680851 (3065 1760);
PAINT MONO (3065 1760);
FORCEPROP 0 LASTPIN (3075 1800) $PN 184
J 2
(3065 1810);
DISPLAY 0.680851 (3065 1810);
PAINT MONO (3065 1810);
FORCEPROP 0 LASTPIN (3075 1850) $PN 186
J 2
(3065 1860);
DISPLAY 0.680851 (3065 1860);
PAINT MONO (3065 1860);
FORCEPROP 0 LASTPIN (3075 1900) $PN 188
J 2
(3065 1910);
DISPLAY 0.680851 (3065 1910);
PAINT MONO (3065 1910);
FORCEPROP 0 LASTPIN (3075 1950) $PN 191
J 2
(3065 1960);
DISPLAY 0.680851 (3065 1960);
PAINT MONO (3065 1960);
FORCEPROP 0 LASTPIN (3075 2000) $PN 193
J 2
(3065 2010);
DISPLAY 0.680851 (3065 2010);
PAINT MONO (3065 2010);
FORCEPROP 0 LASTPIN (3075 2050) $PN 195
J 2
(3065 2060);
DISPLAY 0.680851 (3065 2060);
PAINT MONO (3065 2060);
FORCEPROP 0 LASTPIN (3075 2100) $PN 197
J 2
(3065 2110);
DISPLAY 0.680851 (3065 2110);
PAINT MONO (3065 2110);
FORCEPROP 0 LASTPIN (3075 2150) $PN 199
J 2
(3065 2160);
DISPLAY 0.680851 (3065 2160);
PAINT MONO (3065 2160);
FORCEPROP 0 LASTPIN (3075 2200) $PN 202
J 2
(3065 2210);
DISPLAY 0.680851 (3065 2210);
PAINT MONO (3065 2210);
FORCEPROP 0 LASTPIN (3075 2250) $PN 204
J 2
(3065 2260);
DISPLAY 0.680851 (3065 2260);
PAINT MONO (3065 2260);
FORCEPROP 0 LASTPIN (3075 2300) $PN 206
J 2
(3065 2310);
DISPLAY 0.680851 (3065 2310);
PAINT MONO (3065 2310);
FORCEPROP 0 LASTPIN (3075 2350) $PN 208
J 2
(3065 2360);
DISPLAY 0.680851 (3065 2360);
PAINT MONO (3065 2360);
FORCEPROP 0 LASTPIN (3075 2400) $PN 210
J 2
(3065 2410);
DISPLAY 0.680851 (3065 2410);
PAINT MONO (3065 2410);
FORCEPROP 0 LASTPIN (3075 2450) $PN 212
J 2
(3065 2460);
DISPLAY 0.680851 (3065 2460);
PAINT MONO (3065 2460);
FORCEPROP 0 LASTPIN (3075 2500) $PN 214
J 2
(3065 2510);
DISPLAY 0.680851 (3065 2510);
PAINT MONO (3065 2510);
FORCEPROP 0 LASTPIN (3075 2550) $PN 216
J 2
(3065 2560);
DISPLAY 0.680851 (3065 2560);
PAINT MONO (3065 2560);
FORCEPROP 0 LASTPIN (3075 2600) $PN 219
J 2
(3065 2610);
DISPLAY 0.680851 (3065 2610);
PAINT MONO (3065 2610);
FORCEPROP 0 LASTPIN (3075 2650) $PN 222
J 2
(3065 2660);
DISPLAY 0.680851 (3065 2660);
PAINT MONO (3065 2660);
FORCEPROP 0 LASTPIN (3075 2700) $PN 224
J 2
(3065 2710);
DISPLAY 0.680851 (3065 2710);
PAINT MONO (3065 2710);
FORCEPROP 0 LASTPIN (3075 2750) $PN 226
J 2
(3065 2760);
DISPLAY 0.680851 (3065 2760);
PAINT MONO (3065 2760);
FORCEPROP 0 LASTPIN (3075 2800) $PN 228
J 2
(3065 2810);
DISPLAY 0.680851 (3065 2810);
PAINT MONO (3065 2810);
FORCEPROP 0 LASTPIN (3075 2850) $PN 230
J 2
(3065 2860);
DISPLAY 0.680851 (3065 2860);
PAINT MONO (3065 2860);
FORCEPROP 0 LASTPIN (3075 2900) $PN 233
J 2
(3065 2910);
DISPLAY 0.680851 (3065 2910);
PAINT MONO (3065 2910);
FORCEPROP 0 LASTPIN (3075 2950) $PN 235
J 2
(3065 2960);
DISPLAY 0.680851 (3065 2960);
PAINT MONO (3065 2960);
FORCEPROP 0 LASTPIN (3075 3000) $PN 237
J 2
(3065 3010);
DISPLAY 0.680851 (3065 3010);
PAINT MONO (3065 3010);
FORCEPROP 0 LASTPIN (3075 3050) $PN 240
J 2
(3065 3060);
DISPLAY 0.680851 (3065 3060);
PAINT MONO (3065 3060);
FORCEPROP 0 LASTPIN (3075 3100) $PN 242
J 2
(3065 3110);
DISPLAY 0.680851 (3065 3110);
PAINT MONO (3065 3110);
FORCEPROP 0 LASTPIN (3075 3150) $PN 244
J 2
(3065 3160);
DISPLAY 0.680851 (3065 3160);
PAINT MONO (3065 3160);
FORCEPROP 0 LASTPIN (3075 3200) $PN 246
J 2
(3065 3210);
DISPLAY 0.680851 (3065 3210);
PAINT MONO (3065 3210);
FORCEPROP 0 LASTPIN (3075 3250) $PN 248
J 2
(3065 3260);
DISPLAY 0.680851 (3065 3260);
PAINT MONO (3065 3260);
FORCEPROP 0 LASTPIN (3075 3300) $PN 251
J 2
(3065 3310);
DISPLAY 0.680851 (3065 3310);
PAINT MONO (3065 3310);
FORCEPROP 0 LASTPIN (3075 3350) $PN 253
J 2
(3065 3360);
DISPLAY 0.680851 (3065 3360);
PAINT MONO (3065 3360);
FORCEPROP 0 LASTPIN (3075 3400) $PN 255
J 2
(3065 3410);
DISPLAY 0.680851 (3065 3410);
PAINT MONO (3065 3410);
FORCEPROP 0 LASTPIN (3075 3450) $PN 257
J 2
(3065 3460);
DISPLAY 0.680851 (3065 3460);
PAINT MONO (3065 3460);
FORCEPROP 0 LASTPIN (3075 3500) $PN 259
J 2
(3065 3510);
DISPLAY 0.680851 (3065 3510);
PAINT MONO (3065 3510);
FORCEPROP 0 LASTPIN (3075 3550) $PN 262
J 2
(3065 3560);
DISPLAY 0.680851 (3065 3560);
PAINT MONO (3065 3560);
FORCEPROP 0 LASTPIN (3075 3600) $PN 264
J 2
(3065 3610);
DISPLAY 0.680851 (3065 3610);
PAINT MONO (3065 3610);
FORCEPROP 0 LASTPIN (3075 3650) $PN 266
J 2
(3065 3660);
DISPLAY 0.680851 (3065 3660);
PAINT MONO (3065 3660);
FORCEPROP 0 LASTPIN (3075 3700) $PN 268
J 2
(3065 3710);
DISPLAY 0.680851 (3065 3710);
PAINT MONO (3065 3710);
FORCEPROP 0 LASTPIN (3075 3750) $PN 270
J 2
(3065 3760);
DISPLAY 0.680851 (3065 3760);
PAINT MONO (3065 3760);
FORCEPROP 0 LASTPIN (3075 3800) $PN 273
J 2
(3065 3810);
DISPLAY 0.680851 (3065 3810);
PAINT MONO (3065 3810);
FORCEPROP 0 LASTPIN (3075 3850) $PN 275
J 2
(3065 3860);
DISPLAY 0.680851 (3065 3860);
PAINT MONO (3065 3860);
FORCEPROP 0 LASTPIN (3075 3900) $PN 277
J 2
(3065 3910);
DISPLAY 0.680851 (3065 3910);
PAINT MONO (3065 3910);
FORCEPROP 0 LASTPIN (3075 3950) $PN 279
J 2
(3065 3960);
DISPLAY 0.680851 (3065 3960);
PAINT MONO (3065 3960);
FORCEPROP 0 LASTPIN (3075 4000) $PN 281
J 2
(3065 4010);
DISPLAY 0.680851 (3065 4010);
PAINT MONO (3065 4010);
FORCEPROP 0 LASTPIN (3075 4050) $PN 284
J 2
(3065 4060);
DISPLAY 0.680851 (3065 4060);
PAINT MONO (3065 4060);
FORCEPROP 0 LASTPIN (3075 4100) $PN 286
J 2
(3065 4110);
DISPLAY 0.680851 (3065 4110);
PAINT MONO (3065 4110);
FORCEPROP 0 LASTPIN (3075 4150) $PN 288
J 2
(3065 4160);
DISPLAY 0.680851 (3065 4160);
PAINT MONO (3065 4160);
FORCEPROP 1 LAST NEEDS_NO_SIZE TRUE
J 0
(3675 2675);
DISPLAY 0.723404 (3675 2675);
PAINT GREEN (3675 2675);
DISPLAY INVISIBLE (3675 2675);
FORCEPROP 1 LAST CDS_LMAN_SYM_OUTLINE -450,1775,450,-1775
J 0
(3675 2675);
DISPLAY 0.468085 (3675 2675);
PAINT GREEN (3675 2675);
DISPLAY INVISIBLE (3675 2675);
FORCEPROP 2 LAST CDS_LIB pure_quanta
J 0
(3675 2675);
DISPLAY INVISIBLE (3675 2675);
FORCEPROP 1 LAST PATH I178
J 0
(3675 2675);
DISPLAY 0.723404 (3675 2675);
PAINT GREEN (3675 2675);
DISPLAY INVISIBLE (3675 2675);
FORCEPROP 2 LAST CDS_LOCATION J31
J 0
(3225 4800);
DISPLAY 1.021277 (3225 4800);
DISPLAY INVISIBLE (3225 4800);
FORCEPROP 0 LAST $SEC 3
J 0
(3225 4800);
DISPLAY 0.680851 (3225 4800);
PAINT MONO (3225 4800);
DISPLAY INVISIBLE (3225 4800);
FORCEPROP 2 LAST CDS_SEC 3
J 0
(3225 4800);
DISPLAY 1.021277 (3225 4800);
DISPLAY INVISIBLE (3225 4800);
FORCEADD TAP..1
R 2
(-3250 2300);
FORCEPROP 3 LASTPIN (-3200 2300) SIG_NAME M_H_CPU1_SB_CB<4>
J 0
(-3190 2310);
DISPLAY 0.659574 (-3190 2310);
PAINT MONO (-3190 2310);
DISPLAY INVISIBLE (-3190 2310);
FORCEPROP 1 LASTPIN (-3200 2300) BN 4
J 2
(-3188 2308);
DISPLAY 0.680851 (-3188 2308);
PAINT GREEN (-3188 2308);
FORCEPROP 2 LAST CDS_LIB standard
J 0
(-3250 2300);
DISPLAY INVISIBLE (-3250 2300);
FORCEPROP 1 LAST BODY_TYPE PLUMBING
J 2
(-3250 2350);
DISPLAY 0.872340 (-3250 2350);
PAINT GREEN (-3250 2350);
DISPLAY INVISIBLE (-3250 2350);
FORCEPROP 1 LAST HDL_TAP TRUE
J 2
(-3575 2175);
DISPLAY 0.872340 (-3575 2175);
DISPLAY INVISIBLE (-3575 2175);
FORCEPROP 1 LAST PATH I18
J 2
(-3248 2300);
DISPLAY 0.872340 (-3248 2300);
PAINT GREEN (-3248 2300);
DISPLAY INVISIBLE (-3248 2300);
FORCEADD SCONN288_ADR50017P130CC..1
(-2425 2575);
FORCEPROP 1 LAST PART_NUMBER DFHST8FS461
J 0
(-2870 4597);
DISPLAY 0.723404 (-2870 4597);
PAINT GREEN (-2870 4597);
DISPLAY INVISIBLE (-2870 4597);
FORCEPROP 1 LAST MATERIAL IO
J 0
(-2870 4470);
DISPLAY 0.723404 (-2870 4470);
PAINT GREEN (-2870 4470);
FORCEPROP 2 LAST PART_TYPE SMLF
J 0
(-2875 4750);
DISPLAY 1.021277 (-2875 4750);
FORCEPROP 2 LAST VALUE SCONN288_ADR50017-P130CC
J 0
(-2875 4700);
DISPLAY 1.021277 (-2875 4700);
FORCEPROP 1 LAST $LOCATION J31
J 0
(-2875 4650);
DISPLAY 0.723404 (-2875 4650);
PAINT GREEN (-2875 4650);
FORCEPROP 0 LASTPIN (-3025 1950) $PN 62
J 2
(-3035 1960);
DISPLAY 0.680851 (-3035 1960);
PAINT MONO (-3035 1960);
FORCEPROP 0 LASTPIN (-3025 4000) $PN 66
J 2
(-3035 4010);
DISPLAY 0.680851 (-3035 4010);
PAINT MONO (-3035 4010);
FORCEPROP 0 LASTPIN (-3025 3600) $PN 76
J 2
(-3035 3610);
DISPLAY 0.680851 (-3035 3610);
PAINT MONO (-3035 3610);
FORCEPROP 0 LASTPIN (-3025 4050) $PN 211
J 2
(-3035 4060);
DISPLAY 0.680851 (-3035 4060);
PAINT MONO (-3035 4060);
FORCEPROP 0 LASTPIN (-3025 3650) $PN 221
J 2
(-3035 3660);
DISPLAY 0.680851 (-3035 3660);
PAINT MONO (-3035 3660);
FORCEPROP 0 LASTPIN (-3025 4100) $PN 68
J 2
(-3035 4110);
DISPLAY 0.680851 (-3035 4110);
PAINT MONO (-3035 4110);
FORCEPROP 0 LASTPIN (-3025 3700) $PN 78
J 2
(-3035 3710);
DISPLAY 0.680851 (-3035 3710);
PAINT MONO (-3035 3710);
FORCEPROP 0 LASTPIN (-3025 4150) $PN 213
J 2
(-3035 4160);
DISPLAY 0.680851 (-3035 4160);
PAINT MONO (-3035 4160);
FORCEPROP 0 LASTPIN (-3025 3750) $PN 223
J 2
(-3035 3760);
DISPLAY 0.680851 (-3035 3760);
PAINT MONO (-3035 3760);
FORCEPROP 0 LASTPIN (-3025 4200) $PN 70
J 2
(-3035 4210);
DISPLAY 0.680851 (-3035 4210);
PAINT MONO (-3035 4210);
FORCEPROP 0 LASTPIN (-3025 3800) $PN 80
J 2
(-3035 3810);
DISPLAY 0.680851 (-3035 3810);
PAINT MONO (-3035 3810);
FORCEPROP 0 LASTPIN (-3025 4250) $PN 215
J 2
(-3035 4260);
DISPLAY 0.680851 (-3035 4260);
PAINT MONO (-3035 4260);
FORCEPROP 0 LASTPIN (-3025 3850) $PN 225
J 2
(-3035 3860);
DISPLAY 0.680851 (-3035 3860);
PAINT MONO (-3035 3860);
FORCEPROP 0 LASTPIN (-3025 4300) $PN 72
J 2
(-3035 4310);
DISPLAY 0.680851 (-3035 4310);
PAINT MONO (-3035 4310);
FORCEPROP 0 LASTPIN (-3025 3900) $PN 82
J 2
(-3035 3910);
DISPLAY 0.680851 (-3035 3910);
PAINT MONO (-3035 3910);
FORCEPROP 0 LASTPIN (-3025 2550) $PN 51
J 2
(-3035 2560);
DISPLAY 0.680851 (-3035 2560);
PAINT MONO (-3035 2560);
FORCEPROP 0 LASTPIN (-3025 2100) $PN 96
J 2
(-3035 2110);
DISPLAY 0.680851 (-3035 2110);
PAINT MONO (-3035 2110);
FORCEPROP 0 LASTPIN (-3025 2600) $PN 53
J 2
(-3035 2610);
DISPLAY 0.680851 (-3035 2610);
PAINT MONO (-3035 2610);
FORCEPROP 0 LASTPIN (-3025 2150) $PN 98
J 2
(-3035 2160);
DISPLAY 0.680851 (-3035 2160);
PAINT MONO (-3035 2160);
FORCEPROP 0 LASTPIN (-3025 2650) $PN 196
J 2
(-3035 2660);
DISPLAY 0.680851 (-3035 2660);
PAINT MONO (-3035 2660);
FORCEPROP 0 LASTPIN (-3025 2200) $PN 241
J 2
(-3035 2210);
DISPLAY 0.680851 (-3035 2210);
PAINT MONO (-3035 2210);
FORCEPROP 0 LASTPIN (-3025 2700) $PN 198
J 2
(-3035 2710);
DISPLAY 0.680851 (-3035 2710);
PAINT MONO (-3035 2710);
FORCEPROP 0 LASTPIN (-3025 2250) $PN 243
J 2
(-3035 2260);
DISPLAY 0.680851 (-3035 2260);
PAINT MONO (-3035 2260);
FORCEPROP 0 LASTPIN (-3025 2750) $PN 58
J 2
(-3035 2760);
DISPLAY 0.680851 (-3035 2760);
PAINT MONO (-3035 2760);
FORCEPROP 0 LASTPIN (-3025 2300) $PN 89
J 2
(-3035 2310);
DISPLAY 0.680851 (-3035 2310);
PAINT MONO (-3035 2310);
FORCEPROP 0 LASTPIN (-3025 2800) $PN 60
J 2
(-3035 2810);
DISPLAY 0.680851 (-3035 2810);
PAINT MONO (-3035 2810);
FORCEPROP 0 LASTPIN (-3025 2350) $PN 91
J 2
(-3035 2360);
DISPLAY 0.680851 (-3035 2360);
PAINT MONO (-3035 2360);
FORCEPROP 0 LASTPIN (-3025 2850) $PN 203
J 2
(-3035 2860);
DISPLAY 0.680851 (-3035 2860);
PAINT MONO (-3035 2860);
FORCEPROP 0 LASTPIN (-3025 2400) $PN 234
J 2
(-3035 2410);
DISPLAY 0.680851 (-3035 2410);
PAINT MONO (-3035 2410);
FORCEPROP 0 LASTPIN (-3025 2900) $PN 205
J 2
(-3035 2910);
DISPLAY 0.680851 (-3035 2910);
PAINT MONO (-3035 2910);
FORCEPROP 0 LASTPIN (-3025 2450) $PN 236
J 2
(-3035 2460);
DISPLAY 0.680851 (-3035 2460);
PAINT MONO (-3035 2460);
FORCEPROP 0 LASTPIN (-3025 3000) $PN 218
J 2
(-3035 3010);
DISPLAY 0.680851 (-3035 3010);
PAINT MONO (-3035 3010);
FORCEPROP 0 LASTPIN (-3025 3050) $PN 217
J 2
(-3035 3060);
DISPLAY 0.680851 (-3035 3060);
PAINT MONO (-3035 3060);
FORCEPROP 0 LASTPIN (-3025 3300) $PN 64
J 2
(-3035 3310);
DISPLAY 0.680851 (-3035 3310);
PAINT MONO (-3035 3310);
FORCEPROP 0 LASTPIN (-3025 3150) $PN 84
J 2
(-3035 3160);
DISPLAY 0.680851 (-3035 3160);
PAINT MONO (-3035 3160);
FORCEPROP 0 LASTPIN (-3025 3350) $PN 209
J 2
(-3035 3360);
DISPLAY 0.680851 (-3035 3360);
PAINT MONO (-3035 3360);
FORCEPROP 0 LASTPIN (-3025 3200) $PN 229
J 2
(-3035 3210);
DISPLAY 0.680851 (-3035 3210);
PAINT MONO (-3035 3210);
FORCEPROP 0 LASTPIN (-1825 2750) $PN 7
J 0
(-1815 2760);
DISPLAY 0.680851 (-1815 2760);
PAINT MONO (-1815 2760);
FORCEPROP 0 LASTPIN (-1825 1100) $PN 100
J 0
(-1815 1110);
DISPLAY 0.680851 (-1815 1110);
PAINT MONO (-1815 1110);
FORCEPROP 0 LASTPIN (-1825 2800) $PN 9
J 0
(-1815 2810);
DISPLAY 0.680851 (-1815 2810);
PAINT MONO (-1815 2810);
FORCEPROP 0 LASTPIN (-1825 1150) $PN 102
J 0
(-1815 1160);
DISPLAY 0.680851 (-1815 1160);
PAINT MONO (-1815 1160);
FORCEPROP 0 LASTPIN (-1825 2850) $PN 152
J 0
(-1815 2860);
DISPLAY 0.680851 (-1815 2860);
PAINT MONO (-1815 2860);
FORCEPROP 0 LASTPIN (-1825 1200) $PN 245
J 0
(-1815 1210);
DISPLAY 0.680851 (-1815 1210);
PAINT MONO (-1815 1210);
FORCEPROP 0 LASTPIN (-1825 2900) $PN 154
J 0
(-1815 2910);
DISPLAY 0.680851 (-1815 2910);
PAINT MONO (-1815 2910);
FORCEPROP 0 LASTPIN (-1825 1250) $PN 247
J 0
(-1815 1260);
DISPLAY 0.680851 (-1815 1260);
PAINT MONO (-1815 1260);
FORCEPROP 0 LASTPIN (-1825 2950) $PN 14
J 0
(-1815 2960);
DISPLAY 0.680851 (-1815 2960);
PAINT MONO (-1815 2960);
FORCEPROP 0 LASTPIN (-1825 1300) $PN 107
J 0
(-1815 1310);
DISPLAY 0.680851 (-1815 1310);
PAINT MONO (-1815 1310);
FORCEPROP 0 LASTPIN (-1825 3000) $PN 16
J 0
(-1815 3010);
DISPLAY 0.680851 (-1815 3010);
PAINT MONO (-1815 3010);
FORCEPROP 0 LASTPIN (-1825 1350) $PN 109
J 0
(-1815 1360);
DISPLAY 0.680851 (-1815 1360);
PAINT MONO (-1815 1360);
FORCEPROP 0 LASTPIN (-1825 3050) $PN 159
J 0
(-1815 3060);
DISPLAY 0.680851 (-1815 3060);
PAINT MONO (-1815 3060);
FORCEPROP 0 LASTPIN (-1825 1400) $PN 252
J 0
(-1815 1410);
DISPLAY 0.680851 (-1815 1410);
PAINT MONO (-1815 1410);
FORCEPROP 0 LASTPIN (-1825 3100) $PN 161
J 0
(-1815 3110);
DISPLAY 0.680851 (-1815 3110);
PAINT MONO (-1815 3110);
FORCEPROP 0 LASTPIN (-1825 1450) $PN 254
J 0
(-1815 1460);
DISPLAY 0.680851 (-1815 1460);
PAINT MONO (-1815 1460);
FORCEPROP 0 LASTPIN (-1825 3150) $PN 18
J 0
(-1815 3160);
DISPLAY 0.680851 (-1815 3160);
PAINT MONO (-1815 3160);
FORCEPROP 0 LASTPIN (-1825 1500) $PN 111
J 0
(-1815 1510);
DISPLAY 0.680851 (-1815 1510);
PAINT MONO (-1815 1510);
FORCEPROP 0 LASTPIN (-1825 3200) $PN 20
J 0
(-1815 3210);
DISPLAY 0.680851 (-1815 3210);
PAINT MONO (-1815 3210);
FORCEPROP 0 LASTPIN (-1825 1550) $PN 113
J 0
(-1815 1560);
DISPLAY 0.680851 (-1815 1560);
PAINT MONO (-1815 1560);
FORCEPROP 0 LASTPIN (-1825 3250) $PN 163
J 0
(-1815 3260);
DISPLAY 0.680851 (-1815 3260);
PAINT MONO (-1815 3260);
FORCEPROP 0 LASTPIN (-1825 1600) $PN 256
J 0
(-1815 1610);
DISPLAY 0.680851 (-1815 1610);
PAINT MONO (-1815 1610);
FORCEPROP 0 LASTPIN (-1825 3300) $PN 165
J 0
(-1815 3310);
DISPLAY 0.680851 (-1815 3310);
PAINT MONO (-1815 3310);
FORCEPROP 0 LASTPIN (-1825 1650) $PN 258
J 0
(-1815 1660);
DISPLAY 0.680851 (-1815 1660);
PAINT MONO (-1815 1660);
FORCEPROP 0 LASTPIN (-1825 3350) $PN 25
J 0
(-1815 3360);
DISPLAY 0.680851 (-1815 3360);
PAINT MONO (-1815 3360);
FORCEPROP 0 LASTPIN (-1825 1700) $PN 118
J 0
(-1815 1710);
DISPLAY 0.680851 (-1815 1710);
PAINT MONO (-1815 1710);
FORCEPROP 0 LASTPIN (-1825 3400) $PN 27
J 0
(-1815 3410);
DISPLAY 0.680851 (-1815 3410);
PAINT MONO (-1815 3410);
FORCEPROP 0 LASTPIN (-1825 1750) $PN 120
J 0
(-1815 1760);
DISPLAY 0.680851 (-1815 1760);
PAINT MONO (-1815 1760);
FORCEPROP 0 LASTPIN (-1825 3450) $PN 170
J 0
(-1815 3460);
DISPLAY 0.680851 (-1815 3460);
PAINT MONO (-1815 3460);
FORCEPROP 0 LASTPIN (-1825 1800) $PN 263
J 0
(-1815 1810);
DISPLAY 0.680851 (-1815 1810);
PAINT MONO (-1815 1810);
FORCEPROP 0 LASTPIN (-1825 3500) $PN 172
J 0
(-1815 3510);
DISPLAY 0.680851 (-1815 3510);
PAINT MONO (-1815 3510);
FORCEPROP 0 LASTPIN (-1825 1850) $PN 265
J 0
(-1815 1860);
DISPLAY 0.680851 (-1815 1860);
PAINT MONO (-1815 1860);
FORCEPROP 0 LASTPIN (-1825 3550) $PN 29
J 0
(-1815 3560);
DISPLAY 0.680851 (-1815 3560);
PAINT MONO (-1815 3560);
FORCEPROP 0 LASTPIN (-1825 1900) $PN 122
J 0
(-1815 1910);
DISPLAY 0.680851 (-1815 1910);
PAINT MONO (-1815 1910);
FORCEPROP 0 LASTPIN (-1825 3600) $PN 31
J 0
(-1815 3610);
DISPLAY 0.680851 (-1815 3610);
PAINT MONO (-1815 3610);
FORCEPROP 0 LASTPIN (-1825 1950) $PN 124
J 0
(-1815 1960);
DISPLAY 0.680851 (-1815 1960);
PAINT MONO (-1815 1960);
FORCEPROP 0 LASTPIN (-1825 3650) $PN 174
J 0
(-1815 3660);
DISPLAY 0.680851 (-1815 3660);
PAINT MONO (-1815 3660);
FORCEPROP 0 LASTPIN (-1825 2000) $PN 267
J 0
(-1815 2010);
DISPLAY 0.680851 (-1815 2010);
PAINT MONO (-1815 2010);
FORCEPROP 0 LASTPIN (-1825 3700) $PN 176
J 0
(-1815 3710);
DISPLAY 0.680851 (-1815 3710);
PAINT MONO (-1815 3710);
FORCEPROP 0 LASTPIN (-1825 2050) $PN 269
J 0
(-1815 2060);
DISPLAY 0.680851 (-1815 2060);
PAINT MONO (-1815 2060);
FORCEPROP 0 LASTPIN (-1825 3750) $PN 36
J 0
(-1815 3760);
DISPLAY 0.680851 (-1815 3760);
PAINT MONO (-1815 3760);
FORCEPROP 0 LASTPIN (-1825 2100) $PN 129
J 0
(-1815 2110);
DISPLAY 0.680851 (-1815 2110);
PAINT MONO (-1815 2110);
FORCEPROP 0 LASTPIN (-1825 3800) $PN 38
J 0
(-1815 3810);
DISPLAY 0.680851 (-1815 3810);
PAINT MONO (-1815 3810);
FORCEPROP 0 LASTPIN (-1825 2150) $PN 131
J 0
(-1815 2160);
DISPLAY 0.680851 (-1815 2160);
PAINT MONO (-1815 2160);
FORCEPROP 0 LASTPIN (-1825 3850) $PN 181
J 0
(-1815 3860);
DISPLAY 0.680851 (-1815 3860);
PAINT MONO (-1815 3860);
FORCEPROP 0 LASTPIN (-1825 2200) $PN 274
J 0
(-1815 2210);
DISPLAY 0.680851 (-1815 2210);
PAINT MONO (-1815 2210);
FORCEPROP 0 LASTPIN (-1825 3900) $PN 183
J 0
(-1815 3910);
DISPLAY 0.680851 (-1815 3910);
PAINT MONO (-1815 3910);
FORCEPROP 0 LASTPIN (-1825 2250) $PN 276
J 0
(-1815 2260);
DISPLAY 0.680851 (-1815 2260);
PAINT MONO (-1815 2260);
FORCEPROP 0 LASTPIN (-1825 3950) $PN 40
J 0
(-1815 3960);
DISPLAY 0.680851 (-1815 3960);
PAINT MONO (-1815 3960);
FORCEPROP 0 LASTPIN (-1825 2300) $PN 133
J 0
(-1815 2310);
DISPLAY 0.680851 (-1815 2310);
PAINT MONO (-1815 2310);
FORCEPROP 0 LASTPIN (-1825 4000) $PN 42
J 0
(-1815 4010);
DISPLAY 0.680851 (-1815 4010);
PAINT MONO (-1815 4010);
FORCEPROP 0 LASTPIN (-1825 2350) $PN 135
J 0
(-1815 2360);
DISPLAY 0.680851 (-1815 2360);
PAINT MONO (-1815 2360);
FORCEPROP 0 LASTPIN (-1825 4050) $PN 185
J 0
(-1815 4060);
DISPLAY 0.680851 (-1815 4060);
PAINT MONO (-1815 4060);
FORCEPROP 0 LASTPIN (-1825 2400) $PN 278
J 0
(-1815 2410);
DISPLAY 0.680851 (-1815 2410);
PAINT MONO (-1815 2410);
FORCEPROP 0 LASTPIN (-1825 4100) $PN 187
J 0
(-1815 4110);
DISPLAY 0.680851 (-1815 4110);
PAINT MONO (-1815 4110);
FORCEPROP 0 LASTPIN (-1825 2450) $PN 280
J 0
(-1815 2460);
DISPLAY 0.680851 (-1815 2460);
PAINT MONO (-1815 2460);
FORCEPROP 0 LASTPIN (-1825 4150) $PN 47
J 0
(-1815 4160);
DISPLAY 0.680851 (-1815 4160);
PAINT MONO (-1815 4160);
FORCEPROP 0 LASTPIN (-1825 2500) $PN 140
J 0
(-1815 2510);
DISPLAY 0.680851 (-1815 2510);
PAINT MONO (-1815 2510);
FORCEPROP 0 LASTPIN (-1825 4200) $PN 49
J 0
(-1815 4210);
DISPLAY 0.680851 (-1815 4210);
PAINT MONO (-1815 4210);
FORCEPROP 0 LASTPIN (-1825 2550) $PN 142
J 0
(-1815 2560);
DISPLAY 0.680851 (-1815 2560);
PAINT MONO (-1815 2560);
FORCEPROP 0 LASTPIN (-1825 4250) $PN 192
J 0
(-1815 4260);
DISPLAY 0.680851 (-1815 4260);
PAINT MONO (-1815 4260);
FORCEPROP 0 LASTPIN (-1825 2600) $PN 285
J 0
(-1815 2610);
DISPLAY 0.680851 (-1815 2610);
PAINT MONO (-1815 2610);
FORCEPROP 0 LASTPIN (-1825 4300) $PN 194
J 0
(-1815 4310);
DISPLAY 0.680851 (-1815 4310);
PAINT MONO (-1815 4310);
FORCEPROP 0 LASTPIN (-1825 2650) $PN 287
J 0
(-1815 2660);
DISPLAY 0.680851 (-1815 2660);
PAINT MONO (-1815 2660);
FORCEPROP 0 LASTPIN (-3025 1800) $PN 148
J 2
(-3035 1810);
DISPLAY 0.680851 (-3035 1810);
PAINT MONO (-3035 1810);
FORCEPROP 0 LASTPIN (-3025 1700) $PN 4
J 2
(-3035 1710);
DISPLAY 0.680851 (-3035 1710);
PAINT MONO (-3035 1710);
FORCEPROP 0 LASTPIN (-3025 1750) $PN 5
J 2
(-3035 1760);
DISPLAY 0.680851 (-3035 1760);
PAINT MONO (-3035 1760);
FORCEPROP 0 LASTPIN (-3025 900) $PN 86
J 2
(-3035 910);
DISPLAY 0.680851 (-3035 910);
PAINT MONO (-3035 910);
FORCEPROP 0 LASTPIN (-3025 850) $PN 87
J 2
(-3035 860);
DISPLAY 0.680851 (-3035 860);
PAINT MONO (-3035 860);
FORCEPROP 0 LASTPIN (-3025 3500) $PN 74
J 2
(-3035 3510);
DISPLAY 0.680851 (-3035 3510);
PAINT MONO (-3035 3510);
FORCEPROP 0 LASTPIN (-3025 3450) $PN 227
J 2
(-3035 3460);
DISPLAY 0.680851 (-3035 3460);
PAINT MONO (-3035 3460);
FORCEPROP 0 LASTPIN (-3025 1450) $PN 147
J 2
(-3035 1460);
DISPLAY 0.680851 (-3035 1460);
PAINT MONO (-3035 1460);
FORCEPROP 0 LASTPIN (-3025 2000) $PN 207
J 2
(-3035 2010);
DISPLAY 0.680851 (-3035 2010);
PAINT MONO (-3035 2010);
FORCEPROP 0 LASTPIN (-3025 1050) $PN 2
J 2
(-3035 1060);
DISPLAY 0.680851 (-3035 1060);
PAINT MONO (-3035 1060);
FORCEPROP 0 LASTPIN (-3025 1100) $PN 144
J 2
(-3035 1110);
DISPLAY 0.680851 (-3035 1110);
PAINT MONO (-3035 1110);
FORCEPROP 0 LASTPIN (-3025 1150) $PN 149
J 2
(-3035 1160);
DISPLAY 0.680851 (-3035 1160);
PAINT MONO (-3035 1160);
FORCEPROP 0 LASTPIN (-3025 1200) $PN 150
J 2
(-3035 1210);
DISPLAY 0.680851 (-3035 1210);
PAINT MONO (-3035 1210);
FORCEPROP 0 LASTPIN (-3025 1250) $PN 220
J 2
(-3035 1260);
DISPLAY 0.680851 (-3035 1260);
PAINT MONO (-3035 1260);
FORCEPROP 0 LASTPIN (-3025 1300) $PN 231
J 2
(-3035 1310);
DISPLAY 0.680851 (-3035 1310);
PAINT MONO (-3035 1310);
FORCEPROP 0 LASTPIN (-3025 1350) $PN 232
J 2
(-3035 1360);
DISPLAY 0.680851 (-3035 1360);
PAINT MONO (-3035 1360);
FORCEPROP 0 LASTPIN (-3025 1850) $PN 3
J 2
(-3035 1860);
DISPLAY 0.680851 (-3035 1860);
PAINT MONO (-3035 1860);
FORCEPROP 1 LAST NEEDS_NO_SIZE TRUE
J 0
(-2425 2575);
DISPLAY 0.723404 (-2425 2575);
PAINT GREEN (-2425 2575);
DISPLAY INVISIBLE (-2425 2575);
FORCEPROP 1 LAST CDS_LMAN_SYM_OUTLINE -450,1875,450,-1875
J 0
(-2425 2575);
DISPLAY 0.468085 (-2425 2575);
PAINT GREEN (-2425 2575);
DISPLAY INVISIBLE (-2425 2575);
FORCEPROP 2 LAST CDS_LIB pure_quanta
J 0
(-2425 2575);
DISPLAY INVISIBLE (-2425 2575);
FORCEPROP 1 LAST PATH I180
J 0
(-2425 2575);
DISPLAY 0.723404 (-2425 2575);
PAINT GREEN (-2425 2575);
DISPLAY INVISIBLE (-2425 2575);
FORCEPROP 2 LAST CDS_LOCATION J31
J 0
(-2875 4800);
DISPLAY 1.021277 (-2875 4800);
DISPLAY INVISIBLE (-2875 4800);
FORCEPROP 0 LAST $SEC 1
J 0
(-2850 4800);
DISPLAY 0.680851 (-2850 4800);
PAINT MONO (-2850 4800);
DISPLAY INVISIBLE (-2850 4800);
FORCEPROP 2 LAST CDS_SEC 1
J 0
(-2875 4800);
DISPLAY 1.021277 (-2875 4800);
DISPLAY INVISIBLE (-2875 4800);
FORCEADD SCONN288_ADR50017P130CC..2
(250 3300);
FORCEPROP 1 LAST PART_NUMBER DFHST8FS461
J 0
(-343 4600);
DISPLAY 0.723404 (-343 4600);
PAINT GREEN (-343 4600);
DISPLAY INVISIBLE (-343 4600);
FORCEPROP 2 LAST PART_TYPE SMLF
J 0
(-332 4753);
DISPLAY 1.021277 (-332 4753);
FORCEPROP 2 LAST VALUE SCONN288_ADR50017-P130CC
J 0
(-332 4703);
DISPLAY 1.021277 (-332 4703);
FORCEPROP 1 LAST MATERIAL IO
J 0
(-343 4473);
DISPLAY 0.723404 (-343 4473);
PAINT GREEN (-343 4473);
FORCEPROP 1 LAST LOCATION J31
J 0
(-350 4650);
DISPLAY 0.723404 (-350 4650);
PAINT GREEN (-350 4650);
FORCEPROP 0 LASTPIN (1000 3350) $PN 12
J 0
(1010 3360);
DISPLAY 0.680851 (1010 3360);
PAINT MONO (1010 3360);
FORCEPROP 0 LASTPIN (1000 3400) $PN 11
J 0
(1010 3410);
DISPLAY 0.680851 (1010 3410);
PAINT MONO (1010 3410);
FORCEPROP 0 LASTPIN (1000 2300) $PN 105
J 0
(1010 2310);
DISPLAY 0.680851 (1010 2310);
PAINT MONO (1010 2310);
FORCEPROP 0 LASTPIN (1000 2350) $PN 104
J 0
(1010 2360);
DISPLAY 0.680851 (1010 2360);
PAINT MONO (1010 2360);
FORCEPROP 0 LASTPIN (1000 3450) $PN 23
J 0
(1010 3460);
DISPLAY 0.680851 (1010 3460);
PAINT MONO (1010 3460);
FORCEPROP 0 LASTPIN (1000 3500) $PN 22
J 0
(1010 3510);
DISPLAY 0.680851 (1010 3510);
PAINT MONO (1010 3510);
FORCEPROP 0 LASTPIN (1000 2400) $PN 116
J 0
(1010 2410);
DISPLAY 0.680851 (1010 2410);
PAINT MONO (1010 2410);
FORCEPROP 0 LASTPIN (1000 2450) $PN 115
J 0
(1010 2460);
DISPLAY 0.680851 (1010 2460);
PAINT MONO (1010 2460);
FORCEPROP 0 LASTPIN (1000 3550) $PN 34
J 0
(1010 3560);
DISPLAY 0.680851 (1010 3560);
PAINT MONO (1010 3560);
FORCEPROP 0 LASTPIN (1000 3600) $PN 33
J 0
(1010 3610);
DISPLAY 0.680851 (1010 3610);
PAINT MONO (1010 3610);
FORCEPROP 0 LASTPIN (1000 2500) $PN 127
J 0
(1010 2510);
DISPLAY 0.680851 (1010 2510);
PAINT MONO (1010 2510);
FORCEPROP 0 LASTPIN (1000 2550) $PN 126
J 0
(1010 2560);
DISPLAY 0.680851 (1010 2560);
PAINT MONO (1010 2560);
FORCEPROP 0 LASTPIN (1000 3650) $PN 45
J 0
(1010 3660);
DISPLAY 0.680851 (1010 3660);
PAINT MONO (1010 3660);
FORCEPROP 0 LASTPIN (1000 3700) $PN 44
J 0
(1010 3710);
DISPLAY 0.680851 (1010 3710);
PAINT MONO (1010 3710);
FORCEPROP 0 LASTPIN (1000 2600) $PN 138
J 0
(1010 2610);
DISPLAY 0.680851 (1010 2610);
PAINT MONO (1010 2610);
FORCEPROP 0 LASTPIN (1000 2650) $PN 137
J 0
(1010 2660);
DISPLAY 0.680851 (1010 2660);
PAINT MONO (1010 2660);
FORCEPROP 0 LASTPIN (1000 3750) $PN 56
J 0
(1010 3760);
DISPLAY 0.680851 (1010 3760);
PAINT MONO (1010 3760);
FORCEPROP 0 LASTPIN (1000 3800) $PN 55
J 0
(1010 3810);
DISPLAY 0.680851 (1010 3810);
PAINT MONO (1010 3810);
FORCEPROP 0 LASTPIN (1000 2700) $PN 238
J 0
(1010 2710);
DISPLAY 0.680851 (1010 2710);
PAINT MONO (1010 2710);
FORCEPROP 0 LASTPIN (1000 2750) $PN 239
J 0
(1010 2760);
DISPLAY 0.680851 (1010 2760);
PAINT MONO (1010 2760);
FORCEPROP 0 LASTPIN (1000 3850) $PN 156
J 0
(1010 3860);
DISPLAY 0.680851 (1010 3860);
PAINT MONO (1010 3860);
FORCEPROP 0 LASTPIN (1000 3900) $PN 157
J 0
(1010 3910);
DISPLAY 0.680851 (1010 3910);
PAINT MONO (1010 3910);
FORCEPROP 0 LASTPIN (1000 2800) $PN 249
J 0
(1010 2810);
DISPLAY 0.680851 (1010 2810);
PAINT MONO (1010 2810);
FORCEPROP 0 LASTPIN (1000 2850) $PN 250
J 0
(1010 2860);
DISPLAY 0.680851 (1010 2860);
PAINT MONO (1010 2860);
FORCEPROP 0 LASTPIN (1000 3950) $PN 167
J 0
(1010 3960);
DISPLAY 0.680851 (1010 3960);
PAINT MONO (1010 3960);
FORCEPROP 0 LASTPIN (1000 4000) $PN 168
J 0
(1010 4010);
DISPLAY 0.680851 (1010 4010);
PAINT MONO (1010 4010);
FORCEPROP 0 LASTPIN (1000 2900) $PN 260
J 0
(1010 2910);
DISPLAY 0.680851 (1010 2910);
PAINT MONO (1010 2910);
FORCEPROP 0 LASTPIN (1000 2950) $PN 261
J 0
(1010 2960);
DISPLAY 0.680851 (1010 2960);
PAINT MONO (1010 2960);
FORCEPROP 0 LASTPIN (1000 4050) $PN 178
J 0
(1010 4060);
DISPLAY 0.680851 (1010 4060);
PAINT MONO (1010 4060);
FORCEPROP 0 LASTPIN (1000 4100) $PN 179
J 0
(1010 4110);
DISPLAY 0.680851 (1010 4110);
PAINT MONO (1010 4110);
FORCEPROP 0 LASTPIN (1000 3000) $PN 271
J 0
(1010 3010);
DISPLAY 0.680851 (1010 3010);
PAINT MONO (1010 3010);
FORCEPROP 0 LASTPIN (1000 3050) $PN 272
J 0
(1010 3060);
DISPLAY 0.680851 (1010 3060);
PAINT MONO (1010 3060);
FORCEPROP 0 LASTPIN (1000 4150) $PN 189
J 0
(1010 4160);
DISPLAY 0.680851 (1010 4160);
PAINT MONO (1010 4160);
FORCEPROP 0 LASTPIN (1000 4200) $PN 190
J 0
(1010 4210);
DISPLAY 0.680851 (1010 4210);
PAINT MONO (1010 4210);
FORCEPROP 0 LASTPIN (1000 3100) $PN 282
J 0
(1010 3110);
DISPLAY 0.680851 (1010 3110);
PAINT MONO (1010 3110);
FORCEPROP 0 LASTPIN (1000 3150) $PN 283
J 0
(1010 3160);
DISPLAY 0.680851 (1010 3160);
PAINT MONO (1010 3160);
FORCEPROP 0 LASTPIN (1000 4250) $PN 200
J 0
(1010 4260);
DISPLAY 0.680851 (1010 4260);
PAINT MONO (1010 4260);
FORCEPROP 0 LASTPIN (1000 4300) $PN 201
J 0
(1010 4310);
DISPLAY 0.680851 (1010 4310);
PAINT MONO (1010 4310);
FORCEPROP 0 LASTPIN (1000 3200) $PN 94
J 0
(1010 3210);
DISPLAY 0.680851 (1010 3210);
PAINT MONO (1010 3210);
FORCEPROP 0 LASTPIN (1000 3250) $PN 93
J 0
(1010 3260);
DISPLAY 0.680851 (1010 3260);
PAINT MONO (1010 3260);
FORCEPROP 1 LAST NEEDS_NO_SIZE TRUE
J 0
(250 3300);
DISPLAY 0.723404 (250 3300);
PAINT GREEN (250 3300);
DISPLAY INVISIBLE (250 3300);
FORCEPROP 1 LAST CDS_LMAN_SYM_OUTLINE -600,1150,600,-1150
J 0
(250 3300);
DISPLAY 0.468085 (250 3300);
PAINT GREEN (250 3300);
DISPLAY INVISIBLE (250 3300);
FORCEPROP 2 LAST CDS_LIB pure_quanta
J 0
(250 3300);
DISPLAY INVISIBLE (250 3300);
FORCEPROP 1 LAST PATH I181
J 0
(250 3300);
DISPLAY 0.723404 (250 3300);
PAINT GREEN (250 3300);
DISPLAY INVISIBLE (250 3300);
FORCEPROP 0 LAST $SEC 2
J 0
(-325 4825);
DISPLAY 0.680851 (-325 4825);
PAINT MONO (-325 4825);
DISPLAY INVISIBLE (-325 4825);
FORCEPROP 0 LAST CDS_SEC 2
J 0
(-325 4825);
DISPLAY 1.021277 (-325 4825);
DISPLAY INVISIBLE (-325 4825);
FORCEADD OFFPAGE..1
(-2975 1550);
FORCEPROP 2 LAST $XR7 113 
J 0
(-4067 1550);
DISPLAY 0.638298 (-4067 1550);
PAINT MONO (-4067 1550);
FORCEPROP 2 LAST $XR6 111 
J 0
(-3947 1550);
DISPLAY 0.638298 (-3947 1550);
PAINT MONO (-3947 1550);
FORCEPROP 2 LAST $XR5 110 
J 0
(-3827 1550);
DISPLAY 0.638298 (-3827 1550);
PAINT MONO (-3827 1550);
FORCEPROP 2 LAST $XR4 109 
J 0
(-3707 1550);
DISPLAY 0.638298 (-3707 1550);
PAINT MONO (-3707 1550);
FORCEPROP 2 LAST $XR3 108 
J 0
(-3587 1550);
DISPLAY 0.638298 (-3587 1550);
PAINT MONO (-3587 1550);
FORCEPROP 2 LAST $XR2 107 
J 0
(-3467 1550);
DISPLAY 0.638298 (-3467 1550);
PAINT MONO (-3467 1550);
FORCEPROP 2 LAST $XR1 106 
J 0
(-3347 1550);
DISPLAY 0.638298 (-3347 1550);
PAINT MONO (-3347 1550);
FORCEPROP 2 LAST $XR0 230 
J 0
(-3227 1550);
DISPLAY 0.638298 (-3227 1550);
PAINT MONO (-3227 1550);
FORCEPROP 2 LAST CDS_LIB standard
J 2
(-2975 1550);
DISPLAY INVISIBLE (-2975 1550);
FORCEPROP 1 LAST OFFPAGE TRUE
J 0
(-2650 1425);
DISPLAY 0.872340 (-2650 1425);
DISPLAY INVISIBLE (-2650 1425);
FORCEPROP 1 LAST COMMENT_BODY TRUE
J 0
(-2850 1450);
DISPLAY 0.872340 (-2850 1450);
PAINT GREEN (-2850 1450);
DISPLAY INVISIBLE (-2850 1450);
FORCEPROP 2 LAST PATH I182
J 2
(-3150 1625);
DISPLAY 1.021277 (-3150 1625);
DISPLAY INVISIBLE (-3150 1625);
FORCEADD Q_RES..1
(-4200 1600);
FORCEPROP 1 LAST PART_NUMBER CS04992FB07
J 0
(-4100 1575);
DISPLAY 0.404255 (-4100 1575);
DISPLAY INVISIBLE (-4100 1575);
FORCEPROP 1 LAST VALUE 49.9
J 2
(-3975 1600);
DISPLAY 0.510638 (-3975 1600);
FORCEPROP 1 LAST MATERIAL CHIP
J 0
(-4350 1575);
DISPLAY 0.404255 (-4350 1575);
FORCEPROP 1 LAST $LOCATION R3905
J 0
(-4450 1600);
DISPLAY 0.638298 (-4450 1600);
FORCEPROP 1 LASTPIN (-4300 1600) $PN 1
J 0
(-4288 1612);
DISPLAY 0.787234 (-4288 1612);
PAINT MONO (-4288 1612);
FORCEPROP 1 LASTPIN (-4100 1600) $PN 2
J 0
(-4138 1612);
DISPLAY 0.787234 (-4138 1612);
PAINT MONO (-4138 1612);
FORCEPROP 2 LAST CDS_LIB pure_quanta
J 0
(-4200 1600);
DISPLAY INVISIBLE (-4200 1600);
FORCEPROP 1 LAST PACK_TYPE 0402LF
J 0
(-3900 1600);
DISPLAY 0.510638 (-3900 1600);
DISPLAY INVISIBLE (-3900 1600);
FORCEPROP 1 LAST TOLERANCE 1%
J 0
(-3975 1600);
DISPLAY 0.510638 (-3975 1600);
DISPLAY INVISIBLE (-3975 1600);
FORCEPROP 1 LAST WATTAGE 1/16W
J 2
(-3900 1550);
DISPLAY 0.404255 (-3900 1550);
DISPLAY INVISIBLE (-3900 1550);
FORCEPROP 1 LAST PATH I183
J 0
(-4250 1750);
DISPLAY 0.978723 (-4250 1750);
PAINT WHITE (-4250 1750);
DISPLAY INVISIBLE (-4250 1750);
FORCEPROP 0 LAST CDS_LOCATION R3905
J 0
(-4350 1650);
DISPLAY 1.021277 (-4350 1650);
DISPLAY INVISIBLE (-4350 1650);
FORCEPROP 0 LAST $SEC 1
J 0
(-4350 1650);
DISPLAY 0.680851 (-4350 1650);
PAINT MONO (-4350 1650);
DISPLAY INVISIBLE (-4350 1650);
FORCEPROP 0 LAST CDS_SEC 1
J 0
(-4350 1650);
DISPLAY 1.021277 (-4350 1650);
DISPLAY INVISIBLE (-4350 1650);
FORCEADD TAP..1
R 2
(-3250 2350);
FORCEPROP 3 LASTPIN (-3200 2350) SIG_NAME M_H_CPU1_SB_CB<5>
J 0
(-3190 2360);
DISPLAY 0.659574 (-3190 2360);
PAINT MONO (-3190 2360);
DISPLAY INVISIBLE (-3190 2360);
FORCEPROP 1 LASTPIN (-3200 2350) BN 5
J 2
(-3188 2358);
DISPLAY 0.680851 (-3188 2358);
PAINT GREEN (-3188 2358);
FORCEPROP 2 LAST CDS_LIB standard
J 0
(-3250 2350);
DISPLAY INVISIBLE (-3250 2350);
FORCEPROP 1 LAST BODY_TYPE PLUMBING
J 2
(-3250 2400);
DISPLAY 0.872340 (-3250 2400);
PAINT GREEN (-3250 2400);
DISPLAY INVISIBLE (-3250 2400);
FORCEPROP 1 LAST HDL_TAP TRUE
J 2
(-3575 2225);
DISPLAY 0.872340 (-3575 2225);
DISPLAY INVISIBLE (-3575 2225);
FORCEPROP 1 LAST PATH I19
J 2
(-3248 2350);
DISPLAY 0.872340 (-3248 2350);
PAINT GREEN (-3248 2350);
DISPLAY INVISIBLE (-3248 2350);
FORCEADD UNIVERSAL_GND..1
(-3025 -75);
FORCEPROP 3 LASTPIN (-3025 -25) SIG_NAME GND\g
J 0
(-3015 -15);
DISPLAY 0.659574 (-3015 -15);
PAINT MONO (-3015 -15);
DISPLAY INVISIBLE (-3015 -15);
FORCEPROP 1 LAST PATH I2
J 0
(-2950 -75);
DISPLAY 0.872340 (-2950 -75);
PAINT AQUA (-2950 -75);
DISPLAY INVISIBLE (-2950 -75);
FORCEPROP 1 LAST HDL_POWER GND
J 1
(-3000 -150);
DISPLAY 0.872340 (-3000 -150);
PAINT GREEN (-3000 -150);
DISPLAY INVISIBLE (-3000 -150);
FORCEPROP 2 LAST CDS_LIB logical_power
J 0
(-3025 -75);
PAINT MONO (-3025 -75);
DISPLAY INVISIBLE (-3025 -75);
FORCEADD OFFPAGE..3
R 2
(-4175 2475);
FORCEPROP 2 LAST $XR1 113 
J 0
(-4544 2475);
DISPLAY 0.638298 (-4544 2475);
PAINT MONO (-4544 2475);
FORCEPROP 2 LAST $XR0 58 
J 0
(-4424 2475);
DISPLAY 0.638298 (-4424 2475);
PAINT MONO (-4424 2475);
FORCEPROP 2 LAST CDS_LIB standard
J 0
(-4175 2475);
PAINT MONO (-4175 2475);
DISPLAY INVISIBLE (-4175 2475);
FORCEPROP 1 LAST OFFPAGE TRUE
J 2
(-4500 2350);
DISPLAY 0.872340 (-4500 2350);
DISPLAY INVISIBLE (-4500 2350);
FORCEPROP 1 LAST COMMENT_BODY TRUE
J 2
(-4125 2375);
DISPLAY 0.872340 (-4125 2375);
PAINT GREEN (-4125 2375);
DISPLAY INVISIBLE (-4125 2375);
FORCEPROP 2 LAST PATH I20
J 0
(-4125 2550);
DISPLAY 1.021277 (-4125 2550);
DISPLAY INVISIBLE (-4125 2550);
FORCEADD OFFPAGE..3
R 2
(-4175 2925);
FORCEPROP 2 LAST $XR1 113 
J 0
(-4544 2925);
DISPLAY 0.638298 (-4544 2925);
PAINT MONO (-4544 2925);
FORCEPROP 2 LAST $XR0 58 
J 0
(-4424 2925);
DISPLAY 0.638298 (-4424 2925);
PAINT MONO (-4424 2925);
FORCEPROP 2 LAST CDS_LIB standard
J 0
(-4175 2925);
PAINT MONO (-4175 2925);
DISPLAY INVISIBLE (-4175 2925);
FORCEPROP 1 LAST OFFPAGE TRUE
J 2
(-4500 2800);
DISPLAY 0.872340 (-4500 2800);
DISPLAY INVISIBLE (-4500 2800);
FORCEPROP 1 LAST COMMENT_BODY TRUE
J 2
(-4125 2825);
DISPLAY 0.872340 (-4125 2825);
PAINT GREEN (-4125 2825);
DISPLAY INVISIBLE (-4125 2825);
FORCEPROP 2 LAST PATH I21
J 0
(-4125 3000);
DISPLAY 1.021277 (-4125 3000);
DISPLAY INVISIBLE (-4125 3000);
FORCEADD OFFPAGE..1
(-4175 3000);
FORCEPROP 2 LAST $XR0 58 
J 0
(-4396 3000);
DISPLAY 0.638298 (-4396 3000);
PAINT MONO (-4396 3000);
FORCEPROP 2 LAST CDS_LIB standard
J 0
(-4175 3000);
PAINT MONO (-4175 3000);
DISPLAY INVISIBLE (-4175 3000);
FORCEPROP 1 LAST OFFPAGE TRUE
J 0
(-3850 2875);
DISPLAY 0.872340 (-3850 2875);
DISPLAY INVISIBLE (-3850 2875);
FORCEPROP 1 LAST COMMENT_BODY TRUE
J 0
(-4050 2900);
DISPLAY 0.872340 (-4050 2900);
PAINT GREEN (-4050 2900);
DISPLAY INVISIBLE (-4050 2900);
FORCEPROP 2 LAST PATH I22
J 0
(-4125 3075);
DISPLAY 1.021277 (-4125 3075);
DISPLAY INVISIBLE (-4125 3075);
FORCEADD OFFPAGE..1
(-4175 3050);
FORCEPROP 2 LAST $XR0 58 
J 0
(-4396 3050);
DISPLAY 0.638298 (-4396 3050);
PAINT MONO (-4396 3050);
FORCEPROP 2 LAST CDS_LIB standard
J 0
(-4175 3050);
PAINT MONO (-4175 3050);
DISPLAY INVISIBLE (-4175 3050);
FORCEPROP 1 LAST OFFPAGE TRUE
J 0
(-3850 2925);
DISPLAY 0.872340 (-3850 2925);
DISPLAY INVISIBLE (-3850 2925);
FORCEPROP 1 LAST COMMENT_BODY TRUE
J 0
(-4050 2950);
DISPLAY 0.872340 (-4050 2950);
PAINT GREEN (-4050 2950);
DISPLAY INVISIBLE (-4050 2950);
FORCEPROP 2 LAST PATH I23
J 0
(-4125 3125);
DISPLAY 1.021277 (-4125 3125);
DISPLAY INVISIBLE (-4125 3125);
FORCEADD OFFPAGE..1
(-4175 3150);
FORCEPROP 2 LAST $XR0 58 
J 0
(-4396 3150);
DISPLAY 0.638298 (-4396 3150);
PAINT MONO (-4396 3150);
FORCEPROP 2 LAST CDS_LIB standard
J 0
(-4175 3150);
PAINT MONO (-4175 3150);
DISPLAY INVISIBLE (-4175 3150);
FORCEPROP 1 LAST OFFPAGE TRUE
J 0
(-3850 3025);
DISPLAY 0.872340 (-3850 3025);
DISPLAY INVISIBLE (-3850 3025);
FORCEPROP 1 LAST COMMENT_BODY TRUE
J 0
(-4050 3050);
DISPLAY 0.872340 (-4050 3050);
PAINT GREEN (-4050 3050);
DISPLAY INVISIBLE (-4050 3050);
FORCEPROP 2 LAST PATH I24
J 0
(-4125 3225);
DISPLAY 1.021277 (-4125 3225);
DISPLAY INVISIBLE (-4125 3225);
FORCEADD OFFPAGE..1
(-4175 3200);
FORCEPROP 2 LAST $XR0 58 
J 0
(-4396 3200);
DISPLAY 0.638298 (-4396 3200);
PAINT MONO (-4396 3200);
FORCEPROP 2 LAST CDS_LIB standard
J 0
(-4175 3200);
PAINT MONO (-4175 3200);
DISPLAY INVISIBLE (-4175 3200);
FORCEPROP 1 LAST OFFPAGE TRUE
J 0
(-3850 3075);
DISPLAY 0.872340 (-3850 3075);
DISPLAY INVISIBLE (-3850 3075);
FORCEPROP 1 LAST COMMENT_BODY TRUE
J 0
(-4050 3100);
DISPLAY 0.872340 (-4050 3100);
PAINT GREEN (-4050 3100);
DISPLAY INVISIBLE (-4050 3100);
FORCEPROP 2 LAST PATH I25
J 0
(-4125 3275);
DISPLAY 1.021277 (-4125 3275);
DISPLAY INVISIBLE (-4125 3275);
FORCEADD OFFPAGE..1
(-4175 3300);
FORCEPROP 2 LAST $XR0 58 
J 0
(-4396 3300);
DISPLAY 0.638298 (-4396 3300);
PAINT MONO (-4396 3300);
FORCEPROP 2 LAST CDS_LIB standard
J 0
(-4175 3300);
PAINT MONO (-4175 3300);
DISPLAY INVISIBLE (-4175 3300);
FORCEPROP 1 LAST OFFPAGE TRUE
J 0
(-3850 3175);
DISPLAY 0.872340 (-3850 3175);
DISPLAY INVISIBLE (-3850 3175);
FORCEPROP 1 LAST COMMENT_BODY TRUE
J 0
(-4050 3200);
DISPLAY 0.872340 (-4050 3200);
PAINT GREEN (-4050 3200);
DISPLAY INVISIBLE (-4050 3200);
FORCEPROP 2 LAST PATH I26
J 0
(-4125 3375);
DISPLAY 1.021277 (-4125 3375);
DISPLAY INVISIBLE (-4125 3375);
FORCEADD OFFPAGE..1
(-4175 3350);
FORCEPROP 2 LAST $XR0 58 
J 0
(-4396 3350);
DISPLAY 0.638298 (-4396 3350);
PAINT MONO (-4396 3350);
FORCEPROP 2 LAST CDS_LIB standard
J 0
(-4175 3350);
PAINT MONO (-4175 3350);
DISPLAY INVISIBLE (-4175 3350);
FORCEPROP 1 LAST OFFPAGE TRUE
J 0
(-3850 3225);
DISPLAY 0.872340 (-3850 3225);
DISPLAY INVISIBLE (-3850 3225);
FORCEPROP 1 LAST COMMENT_BODY TRUE
J 0
(-4050 3250);
DISPLAY 0.872340 (-4050 3250);
PAINT GREEN (-4050 3250);
DISPLAY INVISIBLE (-4050 3250);
FORCEPROP 2 LAST PATH I27
J 0
(-4125 3425);
DISPLAY 1.021277 (-4125 3425);
DISPLAY INVISIBLE (-4125 3425);
FORCEADD OFFPAGE..1
(-4175 3500);
FORCEPROP 2 LAST $XR1 113 
J 0
(-4516 3500);
DISPLAY 0.638298 (-4516 3500);
PAINT MONO (-4516 3500);
FORCEPROP 2 LAST $XR0 58 
J 0
(-4396 3500);
DISPLAY 0.638298 (-4396 3500);
PAINT MONO (-4396 3500);
FORCEPROP 2 LAST CDS_LIB standard
J 0
(-4175 3500);
PAINT MONO (-4175 3500);
DISPLAY INVISIBLE (-4175 3500);
FORCEPROP 1 LAST OFFPAGE TRUE
J 0
(-3850 3375);
DISPLAY 0.872340 (-3850 3375);
DISPLAY INVISIBLE (-3850 3375);
FORCEPROP 1 LAST COMMENT_BODY TRUE
J 0
(-4050 3400);
DISPLAY 0.872340 (-4050 3400);
PAINT GREEN (-4050 3400);
DISPLAY INVISIBLE (-4050 3400);
FORCEPROP 2 LAST PATH I28
J 0
(-4125 3575);
DISPLAY 1.021277 (-4125 3575);
DISPLAY INVISIBLE (-4125 3575);
FORCEADD OFFPAGE..1
(-4175 3450);
FORCEPROP 2 LAST $XR1 113 
J 0
(-4516 3450);
DISPLAY 0.638298 (-4516 3450);
PAINT MONO (-4516 3450);
FORCEPROP 2 LAST $XR0 58 
J 0
(-4396 3450);
DISPLAY 0.638298 (-4396 3450);
PAINT MONO (-4396 3450);
FORCEPROP 2 LAST CDS_LIB standard
J 0
(-4175 3450);
PAINT MONO (-4175 3450);
DISPLAY INVISIBLE (-4175 3450);
FORCEPROP 1 LAST OFFPAGE TRUE
J 0
(-3850 3325);
DISPLAY 0.872340 (-3850 3325);
DISPLAY INVISIBLE (-3850 3325);
FORCEPROP 1 LAST COMMENT_BODY TRUE
J 0
(-4050 3350);
DISPLAY 0.872340 (-4050 3350);
PAINT GREEN (-4050 3350);
DISPLAY INVISIBLE (-4050 3350);
FORCEPROP 2 LAST PATH I29
J 0
(-4125 3525);
DISPLAY 1.021277 (-4125 3525);
DISPLAY INVISIBLE (-4125 3525);
FORCEADD Q_RES..2
(-3025 150);
FORCEPROP 1 LAST PART_NUMBER CS41272FB07
J 0
(-2985 25);
DISPLAY 0.978723 (-2985 25);
DISPLAY INVISIBLE (-2985 25);
FORCEPROP 1 LAST VALUE 127K
J 0
(-2980 225);
DISPLAY 0.978723 (-2980 225);
FORCEPROP 1 LAST PACK_TYPE 0402LF
J 0
(-2985 -25);
DISPLAY 0.978723 (-2985 -25);
FORCEPROP 1 LAST TOLERANCE 1%
J 0
(-2980 175);
DISPLAY 0.978723 (-2980 175);
FORCEPROP 1 LAST WATTAGE 1/16W
J 0
(-2985 125);
DISPLAY 0.978723 (-2985 125);
FORCEPROP 1 LAST MATERIAL CHIP
J 0
(-2985 75);
DISPLAY 0.978723 (-2985 75);
FORCEPROP 1 LAST $LOCATION R73
J 0
(-2980 275);
DISPLAY 0.978723 (-2980 275);
FORCEPROP 1 LASTPIN (-3025 250) $PN 1
J 0
(-3020 212);
DISPLAY 0.787234 (-3020 212);
FORCEPROP 1 LASTPIN (-3025 50) $PN 2
J 0
(-3020 60);
DISPLAY 0.787234 (-3020 60);
FORCEPROP 2 LAST CDS_LIB pure_quanta
J 0
(-3025 150);
PAINT MONO (-3025 150);
DISPLAY INVISIBLE (-3025 150);
FORCEPROP 1 LAST PATH I3
J 0
(-2975 325);
DISPLAY 0.978723 (-2975 325);
PAINT WHITE (-2975 325);
DISPLAY INVISIBLE (-2975 325);
FORCEPROP 1 LAST $LOCATION R73
J 0
(-2975 375);
DISPLAY 1.021277 (-2975 375);
DISPLAY INVISIBLE (-2975 375);
FORCEPROP 2 LAST CDS_LOCATION R73
J 0
(-2975 375);
DISPLAY 1.021277 (-2975 375);
DISPLAY INVISIBLE (-2975 375);
FORCEPROP 2 LAST $SEC 1
J 0
(-2975 375);
DISPLAY 0.680851 (-2975 375);
PAINT MONO (-2975 375);
DISPLAY INVISIBLE (-2975 375);
FORCEPROP 2 LAST CDS_SEC 1
J 0
(-2975 375);
DISPLAY 1.021277 (-2975 375);
DISPLAY INVISIBLE (-2975 375);
FORCEADD OFFPAGE..1
(-4175 3925);
FORCEPROP 2 LAST $XR1 113 
J 0
(-4516 3925);
DISPLAY 0.638298 (-4516 3925);
PAINT MONO (-4516 3925);
FORCEPROP 2 LAST $XR0 58 
J 0
(-4396 3925);
DISPLAY 0.638298 (-4396 3925);
PAINT MONO (-4396 3925);
FORCEPROP 2 LAST CDS_LIB standard
J 0
(-4175 3925);
PAINT MONO (-4175 3925);
DISPLAY INVISIBLE (-4175 3925);
FORCEPROP 1 LAST OFFPAGE TRUE
J 0
(-3850 3800);
DISPLAY 0.872340 (-3850 3800);
DISPLAY INVISIBLE (-3850 3800);
FORCEPROP 1 LAST COMMENT_BODY TRUE
J 0
(-4050 3825);
DISPLAY 0.872340 (-4050 3825);
PAINT GREEN (-4050 3825);
DISPLAY INVISIBLE (-4050 3825);
FORCEPROP 2 LAST PATH I30
J 0
(-4125 4000);
DISPLAY 1.021277 (-4125 4000);
DISPLAY INVISIBLE (-4125 4000);
FORCEADD OFFPAGE..1
(-4175 4325);
FORCEPROP 2 LAST $XR1 113 
J 0
(-4516 4325);
DISPLAY 0.638298 (-4516 4325);
PAINT MONO (-4516 4325);
FORCEPROP 2 LAST $XR0 58 
J 0
(-4396 4325);
DISPLAY 0.638298 (-4396 4325);
PAINT MONO (-4396 4325);
FORCEPROP 2 LAST CDS_LIB standard
J 0
(-4175 4325);
PAINT MONO (-4175 4325);
DISPLAY INVISIBLE (-4175 4325);
FORCEPROP 1 LAST OFFPAGE TRUE
J 0
(-3850 4200);
DISPLAY 0.872340 (-3850 4200);
DISPLAY INVISIBLE (-3850 4200);
FORCEPROP 1 LAST COMMENT_BODY TRUE
J 0
(-4050 4225);
DISPLAY 0.872340 (-4050 4225);
PAINT GREEN (-4050 4225);
DISPLAY INVISIBLE (-4050 4225);
FORCEPROP 2 LAST PATH I31
J 0
(-4125 4400);
DISPLAY 1.021277 (-4125 4400);
DISPLAY INVISIBLE (-4125 4400);
FORCEADD TAP..1
R 2
(-3250 2400);
FORCEPROP 3 LASTPIN (-3200 2400) SIG_NAME M_H_CPU1_SB_CB<6>
J 0
(-3190 2410);
DISPLAY 0.659574 (-3190 2410);
PAINT MONO (-3190 2410);
DISPLAY INVISIBLE (-3190 2410);
FORCEPROP 1 LASTPIN (-3200 2400) BN 6
J 2
(-3188 2408);
DISPLAY 0.680851 (-3188 2408);
PAINT GREEN (-3188 2408);
FORCEPROP 2 LAST CDS_LIB standard
J 0
(-3250 2400);
DISPLAY INVISIBLE (-3250 2400);
FORCEPROP 1 LAST BODY_TYPE PLUMBING
J 2
(-3250 2450);
DISPLAY 0.872340 (-3250 2450);
PAINT GREEN (-3250 2450);
DISPLAY INVISIBLE (-3250 2450);
FORCEPROP 1 LAST HDL_TAP TRUE
J 2
(-3575 2275);
DISPLAY 0.872340 (-3575 2275);
DISPLAY INVISIBLE (-3575 2275);
FORCEPROP 1 LAST PATH I32
J 2
(-3248 2400);
DISPLAY 0.872340 (-3248 2400);
PAINT GREEN (-3248 2400);
DISPLAY INVISIBLE (-3248 2400);
FORCEADD TAP..1
R 2
(-3250 2450);
FORCEPROP 3 LASTPIN (-3200 2450) SIG_NAME M_H_CPU1_SB_CB<7>
J 0
(-3190 2460);
DISPLAY 0.659574 (-3190 2460);
PAINT MONO (-3190 2460);
DISPLAY INVISIBLE (-3190 2460);
FORCEPROP 1 LASTPIN (-3200 2450) BN 7
J 2
(-3188 2458);
DISPLAY 0.680851 (-3188 2458);
PAINT GREEN (-3188 2458);
FORCEPROP 2 LAST CDS_LIB standard
J 0
(-3250 2450);
DISPLAY INVISIBLE (-3250 2450);
FORCEPROP 1 LAST BODY_TYPE PLUMBING
J 2
(-3250 2500);
DISPLAY 0.872340 (-3250 2500);
PAINT GREEN (-3250 2500);
DISPLAY INVISIBLE (-3250 2500);
FORCEPROP 1 LAST HDL_TAP TRUE
J 2
(-3575 2325);
DISPLAY 0.872340 (-3575 2325);
DISPLAY INVISIBLE (-3575 2325);
FORCEPROP 1 LAST PATH I33
J 2
(-3248 2450);
DISPLAY 0.872340 (-3248 2450);
PAINT GREEN (-3248 2450);
DISPLAY INVISIBLE (-3248 2450);
FORCEADD TAP..1
R 2
(-3250 2550);
FORCEPROP 3 LASTPIN (-3200 2550) SIG_NAME M_H_CPU1_SA_CB<0>
J 0
(-3190 2560);
DISPLAY 0.659574 (-3190 2560);
PAINT MONO (-3190 2560);
DISPLAY INVISIBLE (-3190 2560);
FORCEPROP 1 LASTPIN (-3200 2550) BN 0
J 2
(-3188 2558);
DISPLAY 0.680851 (-3188 2558);
PAINT GREEN (-3188 2558);
FORCEPROP 2 LAST CDS_LIB standard
J 0
(-3250 2550);
PAINT MONO (-3250 2550);
DISPLAY INVISIBLE (-3250 2550);
FORCEPROP 1 LAST BODY_TYPE PLUMBING
J 2
(-3250 2600);
DISPLAY 0.872340 (-3250 2600);
PAINT GREEN (-3250 2600);
DISPLAY INVISIBLE (-3250 2600);
FORCEPROP 1 LAST HDL_TAP TRUE
J 2
(-3575 2425);
DISPLAY 0.872340 (-3575 2425);
DISPLAY INVISIBLE (-3575 2425);
FORCEPROP 1 LAST PATH I34
J 2
(-3248 2550);
DISPLAY 0.872340 (-3248 2550);
PAINT GREEN (-3248 2550);
DISPLAY INVISIBLE (-3248 2550);
FORCEADD TAP..1
R 2
(-3250 2600);
FORCEPROP 3 LASTPIN (-3200 2600) SIG_NAME M_H_CPU1_SA_CB<1>
J 0
(-3190 2610);
DISPLAY 0.659574 (-3190 2610);
PAINT MONO (-3190 2610);
DISPLAY INVISIBLE (-3190 2610);
FORCEPROP 1 LASTPIN (-3200 2600) BN 1
J 2
(-3188 2608);
DISPLAY 0.680851 (-3188 2608);
PAINT GREEN (-3188 2608);
FORCEPROP 2 LAST CDS_LIB standard
J 0
(-3250 2600);
DISPLAY INVISIBLE (-3250 2600);
FORCEPROP 1 LAST BODY_TYPE PLUMBING
J 2
(-3250 2650);
DISPLAY 0.872340 (-3250 2650);
PAINT GREEN (-3250 2650);
DISPLAY INVISIBLE (-3250 2650);
FORCEPROP 1 LAST HDL_TAP TRUE
J 2
(-3575 2475);
DISPLAY 0.872340 (-3575 2475);
DISPLAY INVISIBLE (-3575 2475);
FORCEPROP 1 LAST PATH I35
J 2
(-3248 2600);
DISPLAY 0.872340 (-3248 2600);
PAINT GREEN (-3248 2600);
DISPLAY INVISIBLE (-3248 2600);
FORCEADD TAP..1
R 2
(-3250 2650);
FORCEPROP 3 LASTPIN (-3200 2650) SIG_NAME M_H_CPU1_SA_CB<2>
J 0
(-3190 2660);
DISPLAY 0.659574 (-3190 2660);
PAINT MONO (-3190 2660);
DISPLAY INVISIBLE (-3190 2660);
FORCEPROP 1 LASTPIN (-3200 2650) BN 2
J 2
(-3188 2658);
DISPLAY 0.680851 (-3188 2658);
PAINT GREEN (-3188 2658);
FORCEPROP 2 LAST CDS_LIB standard
J 0
(-3250 2650);
DISPLAY INVISIBLE (-3250 2650);
FORCEPROP 1 LAST BODY_TYPE PLUMBING
J 2
(-3250 2700);
DISPLAY 0.872340 (-3250 2700);
PAINT GREEN (-3250 2700);
DISPLAY INVISIBLE (-3250 2700);
FORCEPROP 1 LAST HDL_TAP TRUE
J 2
(-3575 2525);
DISPLAY 0.872340 (-3575 2525);
DISPLAY INVISIBLE (-3575 2525);
FORCEPROP 1 LAST PATH I36
J 2
(-3248 2650);
DISPLAY 0.872340 (-3248 2650);
PAINT GREEN (-3248 2650);
DISPLAY INVISIBLE (-3248 2650);
FORCEADD TAP..1
R 2
(-3250 2700);
FORCEPROP 3 LASTPIN (-3200 2700) SIG_NAME M_H_CPU1_SA_CB<3>
J 0
(-3190 2710);
DISPLAY 0.659574 (-3190 2710);
PAINT MONO (-3190 2710);
DISPLAY INVISIBLE (-3190 2710);
FORCEPROP 1 LASTPIN (-3200 2700) BN 3
J 2
(-3188 2708);
DISPLAY 0.680851 (-3188 2708);
PAINT GREEN (-3188 2708);
FORCEPROP 2 LAST CDS_LIB standard
J 0
(-3250 2700);
DISPLAY INVISIBLE (-3250 2700);
FORCEPROP 1 LAST BODY_TYPE PLUMBING
J 2
(-3250 2750);
DISPLAY 0.872340 (-3250 2750);
PAINT GREEN (-3250 2750);
DISPLAY INVISIBLE (-3250 2750);
FORCEPROP 1 LAST HDL_TAP TRUE
J 2
(-3575 2575);
DISPLAY 0.872340 (-3575 2575);
DISPLAY INVISIBLE (-3575 2575);
FORCEPROP 1 LAST PATH I37
J 2
(-3248 2700);
DISPLAY 0.872340 (-3248 2700);
PAINT GREEN (-3248 2700);
DISPLAY INVISIBLE (-3248 2700);
FORCEADD TAP..1
R 2
(-3250 2750);
FORCEPROP 3 LASTPIN (-3200 2750) SIG_NAME M_H_CPU1_SA_CB<4>
J 0
(-3190 2760);
DISPLAY 0.659574 (-3190 2760);
PAINT MONO (-3190 2760);
DISPLAY INVISIBLE (-3190 2760);
FORCEPROP 1 LASTPIN (-3200 2750) BN 4
J 2
(-3188 2758);
DISPLAY 0.680851 (-3188 2758);
PAINT GREEN (-3188 2758);
FORCEPROP 2 LAST CDS_LIB standard
J 0
(-3250 2750);
DISPLAY INVISIBLE (-3250 2750);
FORCEPROP 1 LAST BODY_TYPE PLUMBING
J 2
(-3250 2800);
DISPLAY 0.872340 (-3250 2800);
PAINT GREEN (-3250 2800);
DISPLAY INVISIBLE (-3250 2800);
FORCEPROP 1 LAST HDL_TAP TRUE
J 2
(-3575 2625);
DISPLAY 0.872340 (-3575 2625);
DISPLAY INVISIBLE (-3575 2625);
FORCEPROP 1 LAST PATH I38
J 2
(-3248 2750);
DISPLAY 0.872340 (-3248 2750);
PAINT GREEN (-3248 2750);
DISPLAY INVISIBLE (-3248 2750);
FORCEADD TAP..1
R 2
(-3250 2800);
FORCEPROP 3 LASTPIN (-3200 2800) SIG_NAME M_H_CPU1_SA_CB<5>
J 0
(-3190 2810);
DISPLAY 0.659574 (-3190 2810);
PAINT MONO (-3190 2810);
DISPLAY INVISIBLE (-3190 2810);
FORCEPROP 1 LASTPIN (-3200 2800) BN 5
J 2
(-3188 2808);
DISPLAY 0.680851 (-3188 2808);
PAINT GREEN (-3188 2808);
FORCEPROP 2 LAST CDS_LIB standard
J 0
(-3250 2800);
DISPLAY INVISIBLE (-3250 2800);
FORCEPROP 1 LAST BODY_TYPE PLUMBING
J 2
(-3250 2850);
DISPLAY 0.872340 (-3250 2850);
PAINT GREEN (-3250 2850);
DISPLAY INVISIBLE (-3250 2850);
FORCEPROP 1 LAST HDL_TAP TRUE
J 2
(-3575 2675);
DISPLAY 0.872340 (-3575 2675);
DISPLAY INVISIBLE (-3575 2675);
FORCEPROP 1 LAST PATH I39
J 2
(-3248 2800);
DISPLAY 0.872340 (-3248 2800);
PAINT GREEN (-3248 2800);
DISPLAY INVISIBLE (-3248 2800);
FORCEADD OFFPAGE..2
R 2
(-4175 900);
FORCEPROP 2 LAST $XR0 58 
J 0
(-4429 900);
DISPLAY 0.638298 (-4429 900);
PAINT MONO (-4429 900);
FORCEPROP 2 LAST CDS_LIB standard
J 0
(-4175 900);
PAINT MONO (-4175 900);
DISPLAY INVISIBLE (-4175 900);
FORCEPROP 1 LAST OFFPAGE TRUE
J 2
(-4500 775);
DISPLAY 0.872340 (-4500 775);
DISPLAY INVISIBLE (-4500 775);
FORCEPROP 1 LAST COMMENT_BODY TRUE
J 2
(-4130 805);
DISPLAY 0.872340 (-4130 805);
PAINT GREEN (-4130 805);
DISPLAY INVISIBLE (-4130 805);
FORCEPROP 2 LAST PATH I4
J 0
(-4125 975);
DISPLAY 1.021277 (-4125 975);
DISPLAY INVISIBLE (-4125 975);
FORCEADD TAP..1
R 2
(-3250 2850);
FORCEPROP 3 LASTPIN (-3200 2850) SIG_NAME M_H_CPU1_SA_CB<6>
J 0
(-3190 2860);
DISPLAY 0.659574 (-3190 2860);
PAINT MONO (-3190 2860);
DISPLAY INVISIBLE (-3190 2860);
FORCEPROP 1 LASTPIN (-3200 2850) BN 6
J 2
(-3188 2858);
DISPLAY 0.680851 (-3188 2858);
PAINT GREEN (-3188 2858);
FORCEPROP 2 LAST CDS_LIB standard
J 0
(-3250 2850);
DISPLAY INVISIBLE (-3250 2850);
FORCEPROP 1 LAST BODY_TYPE PLUMBING
J 2
(-3250 2900);
DISPLAY 0.872340 (-3250 2900);
PAINT GREEN (-3250 2900);
DISPLAY INVISIBLE (-3250 2900);
FORCEPROP 1 LAST HDL_TAP TRUE
J 2
(-3575 2725);
DISPLAY 0.872340 (-3575 2725);
DISPLAY INVISIBLE (-3575 2725);
FORCEPROP 1 LAST PATH I40
J 2
(-3248 2850);
DISPLAY 0.872340 (-3248 2850);
PAINT GREEN (-3248 2850);
DISPLAY INVISIBLE (-3248 2850);
FORCEADD TAP..1
R 2
(-3250 2900);
FORCEPROP 3 LASTPIN (-3200 2900) SIG_NAME M_H_CPU1_SA_CB<7>
J 0
(-3190 2910);
DISPLAY 0.659574 (-3190 2910);
PAINT MONO (-3190 2910);
DISPLAY INVISIBLE (-3190 2910);
FORCEPROP 1 LASTPIN (-3200 2900) BN 7
J 2
(-3188 2908);
DISPLAY 0.680851 (-3188 2908);
PAINT GREEN (-3188 2908);
FORCEPROP 2 LAST CDS_LIB standard
J 0
(-3250 2900);
DISPLAY INVISIBLE (-3250 2900);
FORCEPROP 1 LAST BODY_TYPE PLUMBING
J 2
(-3250 2950);
DISPLAY 0.872340 (-3250 2950);
PAINT GREEN (-3250 2950);
DISPLAY INVISIBLE (-3250 2950);
FORCEPROP 1 LAST HDL_TAP TRUE
J 2
(-3575 2775);
DISPLAY 0.872340 (-3575 2775);
DISPLAY INVISIBLE (-3575 2775);
FORCEPROP 1 LAST PATH I41
J 2
(-3248 2900);
DISPLAY 0.872340 (-3248 2900);
PAINT GREEN (-3248 2900);
DISPLAY INVISIBLE (-3248 2900);
FORCEADD TAP..1
R 2
(-3250 3650);
FORCEPROP 3 LASTPIN (-3200 3650) SIG_NAME M_H_CPU1_SB_CA<1>
J 0
(-3190 3660);
DISPLAY 0.659574 (-3190 3660);
PAINT MONO (-3190 3660);
DISPLAY INVISIBLE (-3190 3660);
FORCEPROP 1 LASTPIN (-3200 3650) BN 1
J 2
(-3188 3658);
DISPLAY 0.680851 (-3188 3658);
PAINT GREEN (-3188 3658);
FORCEPROP 2 LAST CDS_LIB standard
J 0
(-3250 3650);
DISPLAY INVISIBLE (-3250 3650);
FORCEPROP 1 LAST BODY_TYPE PLUMBING
J 2
(-3250 3700);
DISPLAY 0.872340 (-3250 3700);
PAINT GREEN (-3250 3700);
DISPLAY INVISIBLE (-3250 3700);
FORCEPROP 1 LAST HDL_TAP TRUE
J 2
(-3575 3525);
DISPLAY 0.872340 (-3575 3525);
DISPLAY INVISIBLE (-3575 3525);
FORCEPROP 1 LAST PATH I42
J 2
(-3248 3650);
DISPLAY 0.872340 (-3248 3650);
PAINT GREEN (-3248 3650);
DISPLAY INVISIBLE (-3248 3650);
FORCEADD TAP..1
R 2
(-3250 3600);
FORCEPROP 3 LASTPIN (-3200 3600) SIG_NAME M_H_CPU1_SB_CA<0>
J 0
(-3190 3610);
DISPLAY 0.659574 (-3190 3610);
PAINT MONO (-3190 3610);
DISPLAY INVISIBLE (-3190 3610);
FORCEPROP 1 LASTPIN (-3200 3600) BN 0
J 2
(-3188 3608);
DISPLAY 0.680851 (-3188 3608);
PAINT GREEN (-3188 3608);
FORCEPROP 2 LAST CDS_LIB standard
J 0
(-3250 3600);
DISPLAY INVISIBLE (-3250 3600);
FORCEPROP 1 LAST BODY_TYPE PLUMBING
J 2
(-3250 3650);
DISPLAY 0.872340 (-3250 3650);
PAINT GREEN (-3250 3650);
DISPLAY INVISIBLE (-3250 3650);
FORCEPROP 1 LAST HDL_TAP TRUE
J 2
(-3575 3475);
DISPLAY 0.872340 (-3575 3475);
DISPLAY INVISIBLE (-3575 3475);
FORCEPROP 1 LAST PATH I43
J 2
(-3248 3600);
DISPLAY 0.872340 (-3248 3600);
PAINT GREEN (-3248 3600);
DISPLAY INVISIBLE (-3248 3600);
FORCEADD TAP..1
R 2
(-3250 3700);
FORCEPROP 3 LASTPIN (-3200 3700) SIG_NAME M_H_CPU1_SB_CA<2>
J 0
(-3190 3710);
DISPLAY 0.659574 (-3190 3710);
PAINT MONO (-3190 3710);
DISPLAY INVISIBLE (-3190 3710);
FORCEPROP 1 LASTPIN (-3200 3700) BN 2
J 2
(-3188 3708);
DISPLAY 0.680851 (-3188 3708);
PAINT GREEN (-3188 3708);
FORCEPROP 2 LAST CDS_LIB standard
J 0
(-3250 3700);
DISPLAY INVISIBLE (-3250 3700);
FORCEPROP 1 LAST BODY_TYPE PLUMBING
J 2
(-3250 3750);
DISPLAY 0.872340 (-3250 3750);
PAINT GREEN (-3250 3750);
DISPLAY INVISIBLE (-3250 3750);
FORCEPROP 1 LAST HDL_TAP TRUE
J 2
(-3575 3575);
DISPLAY 0.872340 (-3575 3575);
DISPLAY INVISIBLE (-3575 3575);
FORCEPROP 1 LAST PATH I44
J 2
(-3248 3700);
DISPLAY 0.872340 (-3248 3700);
PAINT GREEN (-3248 3700);
DISPLAY INVISIBLE (-3248 3700);
FORCEADD TAP..1
R 2
(-3250 3750);
FORCEPROP 3 LASTPIN (-3200 3750) SIG_NAME M_H_CPU1_SB_CA<3>
J 0
(-3190 3760);
DISPLAY 0.659574 (-3190 3760);
PAINT MONO (-3190 3760);
DISPLAY INVISIBLE (-3190 3760);
FORCEPROP 1 LASTPIN (-3200 3750) BN 3
J 2
(-3188 3758);
DISPLAY 0.680851 (-3188 3758);
PAINT GREEN (-3188 3758);
FORCEPROP 2 LAST CDS_LIB standard
J 0
(-3250 3750);
DISPLAY INVISIBLE (-3250 3750);
FORCEPROP 1 LAST BODY_TYPE PLUMBING
J 2
(-3250 3800);
DISPLAY 0.872340 (-3250 3800);
PAINT GREEN (-3250 3800);
DISPLAY INVISIBLE (-3250 3800);
FORCEPROP 1 LAST HDL_TAP TRUE
J 2
(-3575 3625);
DISPLAY 0.872340 (-3575 3625);
DISPLAY INVISIBLE (-3575 3625);
FORCEPROP 1 LAST PATH I45
J 2
(-3248 3750);
DISPLAY 0.872340 (-3248 3750);
PAINT GREEN (-3248 3750);
DISPLAY INVISIBLE (-3248 3750);
FORCEADD TAP..1
R 2
(-3250 3800);
FORCEPROP 3 LASTPIN (-3200 3800) SIG_NAME M_H_CPU1_SB_CA<4>
J 0
(-3190 3810);
DISPLAY 0.659574 (-3190 3810);
PAINT MONO (-3190 3810);
DISPLAY INVISIBLE (-3190 3810);
FORCEPROP 1 LASTPIN (-3200 3800) BN 4
J 2
(-3188 3808);
DISPLAY 0.680851 (-3188 3808);
PAINT GREEN (-3188 3808);
FORCEPROP 2 LAST CDS_LIB standard
J 0
(-3250 3800);
DISPLAY INVISIBLE (-3250 3800);
FORCEPROP 1 LAST BODY_TYPE PLUMBING
J 2
(-3250 3850);
DISPLAY 0.872340 (-3250 3850);
PAINT GREEN (-3250 3850);
DISPLAY INVISIBLE (-3250 3850);
FORCEPROP 1 LAST HDL_TAP TRUE
J 2
(-3575 3675);
DISPLAY 0.872340 (-3575 3675);
DISPLAY INVISIBLE (-3575 3675);
FORCEPROP 1 LAST PATH I46
J 2
(-3248 3800);
DISPLAY 0.872340 (-3248 3800);
PAINT GREEN (-3248 3800);
DISPLAY INVISIBLE (-3248 3800);
FORCEADD TAP..1
R 2
(-3250 3900);
FORCEPROP 3 LASTPIN (-3200 3900) SIG_NAME M_H_CPU1_SB_CA<6>
J 0
(-3190 3910);
DISPLAY 0.659574 (-3190 3910);
PAINT MONO (-3190 3910);
DISPLAY INVISIBLE (-3190 3910);
FORCEPROP 1 LASTPIN (-3200 3900) BN 6
J 2
(-3188 3908);
DISPLAY 0.680851 (-3188 3908);
PAINT GREEN (-3188 3908);
FORCEPROP 2 LAST CDS_LIB standard
J 0
(-3250 3900);
DISPLAY INVISIBLE (-3250 3900);
FORCEPROP 1 LAST BODY_TYPE PLUMBING
J 2
(-3250 3950);
DISPLAY 0.872340 (-3250 3950);
PAINT GREEN (-3250 3950);
DISPLAY INVISIBLE (-3250 3950);
FORCEPROP 1 LAST HDL_TAP TRUE
J 2
(-3575 3775);
DISPLAY 0.872340 (-3575 3775);
DISPLAY INVISIBLE (-3575 3775);
FORCEPROP 1 LAST PATH I47
J 2
(-3248 3900);
DISPLAY 0.872340 (-3248 3900);
PAINT GREEN (-3248 3900);
DISPLAY INVISIBLE (-3248 3900);
FORCEADD TAP..1
R 2
(-3250 3850);
FORCEPROP 3 LASTPIN (-3200 3850) SIG_NAME M_H_CPU1_SB_CA<5>
J 0
(-3190 3860);
DISPLAY 0.659574 (-3190 3860);
PAINT MONO (-3190 3860);
DISPLAY INVISIBLE (-3190 3860);
FORCEPROP 1 LASTPIN (-3200 3850) BN 5
J 2
(-3188 3858);
DISPLAY 0.680851 (-3188 3858);
PAINT GREEN (-3188 3858);
FORCEPROP 2 LAST CDS_LIB standard
J 0
(-3250 3850);
DISPLAY INVISIBLE (-3250 3850);
FORCEPROP 1 LAST BODY_TYPE PLUMBING
J 2
(-3250 3900);
DISPLAY 0.872340 (-3250 3900);
PAINT GREEN (-3250 3900);
DISPLAY INVISIBLE (-3250 3900);
FORCEPROP 1 LAST HDL_TAP TRUE
J 2
(-3575 3725);
DISPLAY 0.872340 (-3575 3725);
DISPLAY INVISIBLE (-3575 3725);
FORCEPROP 1 LAST PATH I48
J 2
(-3248 3850);
DISPLAY 0.872340 (-3248 3850);
PAINT GREEN (-3248 3850);
DISPLAY INVISIBLE (-3248 3850);
FORCEADD TAP..1
R 2
(-3250 4000);
FORCEPROP 3 LASTPIN (-3200 4000) SIG_NAME M_H_CPU1_SA_CA<0>
J 0
(-3190 4010);
DISPLAY 0.659574 (-3190 4010);
PAINT MONO (-3190 4010);
DISPLAY INVISIBLE (-3190 4010);
FORCEPROP 1 LASTPIN (-3200 4000) BN 0
J 2
(-3188 4008);
DISPLAY 0.680851 (-3188 4008);
PAINT GREEN (-3188 4008);
FORCEPROP 2 LAST CDS_LIB standard
J 0
(-3250 4000);
DISPLAY INVISIBLE (-3250 4000);
FORCEPROP 1 LAST BODY_TYPE PLUMBING
J 2
(-3250 4050);
DISPLAY 0.872340 (-3250 4050);
PAINT GREEN (-3250 4050);
DISPLAY INVISIBLE (-3250 4050);
FORCEPROP 1 LAST HDL_TAP TRUE
J 2
(-3575 3875);
DISPLAY 0.872340 (-3575 3875);
DISPLAY INVISIBLE (-3575 3875);
FORCEPROP 1 LAST PATH I49
J 2
(-3248 4000);
DISPLAY 0.872340 (-3248 4000);
PAINT GREEN (-3248 4000);
DISPLAY INVISIBLE (-3248 4000);
FORCEADD OFFPAGE..2
R 2
(-4175 850);
FORCEPROP 2 LAST $XR0 58 
J 0
(-4429 850);
DISPLAY 0.638298 (-4429 850);
PAINT MONO (-4429 850);
FORCEPROP 2 LAST CDS_LIB standard
J 0
(-4175 850);
PAINT MONO (-4175 850);
DISPLAY INVISIBLE (-4175 850);
FORCEPROP 1 LAST OFFPAGE TRUE
J 2
(-4500 725);
DISPLAY 0.872340 (-4500 725);
DISPLAY INVISIBLE (-4500 725);
FORCEPROP 1 LAST COMMENT_BODY TRUE
J 2
(-4130 755);
DISPLAY 0.872340 (-4130 755);
PAINT GREEN (-4130 755);
DISPLAY INVISIBLE (-4130 755);
FORCEPROP 2 LAST PATH I5
J 0
(-4125 925);
DISPLAY 1.021277 (-4125 925);
DISPLAY INVISIBLE (-4125 925);
FORCEADD TAP..1
R 2
(-3250 4100);
FORCEPROP 3 LASTPIN (-3200 4100) SIG_NAME M_H_CPU1_SA_CA<2>
J 0
(-3190 4110);
DISPLAY 0.659574 (-3190 4110);
PAINT MONO (-3190 4110);
DISPLAY INVISIBLE (-3190 4110);
FORCEPROP 1 LASTPIN (-3200 4100) BN 2
J 2
(-3188 4108);
DISPLAY 0.680851 (-3188 4108);
PAINT GREEN (-3188 4108);
FORCEPROP 2 LAST CDS_LIB standard
J 0
(-3250 4100);
DISPLAY INVISIBLE (-3250 4100);
FORCEPROP 1 LAST BODY_TYPE PLUMBING
J 2
(-3250 4150);
DISPLAY 0.872340 (-3250 4150);
PAINT GREEN (-3250 4150);
DISPLAY INVISIBLE (-3250 4150);
FORCEPROP 1 LAST HDL_TAP TRUE
J 2
(-3575 3975);
DISPLAY 0.872340 (-3575 3975);
DISPLAY INVISIBLE (-3575 3975);
FORCEPROP 1 LAST PATH I50
J 2
(-3248 4100);
DISPLAY 0.872340 (-3248 4100);
PAINT GREEN (-3248 4100);
DISPLAY INVISIBLE (-3248 4100);
FORCEADD TAP..1
R 2
(-3250 4050);
FORCEPROP 3 LASTPIN (-3200 4050) SIG_NAME M_H_CPU1_SA_CA<1>
J 0
(-3190 4060);
DISPLAY 0.659574 (-3190 4060);
PAINT MONO (-3190 4060);
DISPLAY INVISIBLE (-3190 4060);
FORCEPROP 1 LASTPIN (-3200 4050) BN 1
J 2
(-3188 4058);
DISPLAY 0.680851 (-3188 4058);
PAINT GREEN (-3188 4058);
FORCEPROP 2 LAST CDS_LIB standard
J 0
(-3250 4050);
DISPLAY INVISIBLE (-3250 4050);
FORCEPROP 1 LAST BODY_TYPE PLUMBING
J 2
(-3250 4100);
DISPLAY 0.872340 (-3250 4100);
PAINT GREEN (-3250 4100);
DISPLAY INVISIBLE (-3250 4100);
FORCEPROP 1 LAST HDL_TAP TRUE
J 2
(-3575 3925);
DISPLAY 0.872340 (-3575 3925);
DISPLAY INVISIBLE (-3575 3925);
FORCEPROP 1 LAST PATH I51
J 2
(-3248 4050);
DISPLAY 0.872340 (-3248 4050);
PAINT GREEN (-3248 4050);
DISPLAY INVISIBLE (-3248 4050);
FORCEADD TAP..1
R 2
(-3250 4150);
FORCEPROP 3 LASTPIN (-3200 4150) SIG_NAME M_H_CPU1_SA_CA<3>
J 0
(-3190 4160);
DISPLAY 0.659574 (-3190 4160);
PAINT MONO (-3190 4160);
DISPLAY INVISIBLE (-3190 4160);
FORCEPROP 1 LASTPIN (-3200 4150) BN 3
J 2
(-3188 4158);
DISPLAY 0.680851 (-3188 4158);
PAINT GREEN (-3188 4158);
FORCEPROP 2 LAST CDS_LIB standard
J 0
(-3250 4150);
DISPLAY INVISIBLE (-3250 4150);
FORCEPROP 1 LAST BODY_TYPE PLUMBING
J 2
(-3250 4200);
DISPLAY 0.872340 (-3250 4200);
PAINT GREEN (-3250 4200);
DISPLAY INVISIBLE (-3250 4200);
FORCEPROP 1 LAST HDL_TAP TRUE
J 2
(-3575 4025);
DISPLAY 0.872340 (-3575 4025);
DISPLAY INVISIBLE (-3575 4025);
FORCEPROP 1 LAST PATH I52
J 2
(-3248 4150);
DISPLAY 0.872340 (-3248 4150);
PAINT GREEN (-3248 4150);
DISPLAY INVISIBLE (-3248 4150);
FORCEADD TAP..1
R 2
(-3250 4200);
FORCEPROP 3 LASTPIN (-3200 4200) SIG_NAME M_H_CPU1_SA_CA<4>
J 0
(-3190 4210);
DISPLAY 0.659574 (-3190 4210);
PAINT MONO (-3190 4210);
DISPLAY INVISIBLE (-3190 4210);
FORCEPROP 1 LASTPIN (-3200 4200) BN 4
J 2
(-3188 4208);
DISPLAY 0.680851 (-3188 4208);
PAINT GREEN (-3188 4208);
FORCEPROP 2 LAST CDS_LIB standard
J 0
(-3250 4200);
DISPLAY INVISIBLE (-3250 4200);
FORCEPROP 1 LAST BODY_TYPE PLUMBING
J 2
(-3250 4250);
DISPLAY 0.872340 (-3250 4250);
PAINT GREEN (-3250 4250);
DISPLAY INVISIBLE (-3250 4250);
FORCEPROP 1 LAST HDL_TAP TRUE
J 2
(-3575 4075);
DISPLAY 0.872340 (-3575 4075);
DISPLAY INVISIBLE (-3575 4075);
FORCEPROP 1 LAST PATH I53
J 2
(-3248 4200);
DISPLAY 0.872340 (-3248 4200);
PAINT GREEN (-3248 4200);
DISPLAY INVISIBLE (-3248 4200);
FORCEADD TAP..1
R 2
(-3250 4250);
FORCEPROP 3 LASTPIN (-3200 4250) SIG_NAME M_H_CPU1_SA_CA<5>
J 0
(-3190 4260);
DISPLAY 0.659574 (-3190 4260);
PAINT MONO (-3190 4260);
DISPLAY INVISIBLE (-3190 4260);
FORCEPROP 1 LASTPIN (-3200 4250) BN 5
J 2
(-3188 4258);
DISPLAY 0.680851 (-3188 4258);
PAINT GREEN (-3188 4258);
FORCEPROP 2 LAST CDS_LIB standard
J 0
(-3250 4250);
DISPLAY INVISIBLE (-3250 4250);
FORCEPROP 1 LAST BODY_TYPE PLUMBING
J 2
(-3250 4300);
DISPLAY 0.872340 (-3250 4300);
PAINT GREEN (-3250 4300);
DISPLAY INVISIBLE (-3250 4300);
FORCEPROP 1 LAST HDL_TAP TRUE
J 2
(-3575 4125);
DISPLAY 0.872340 (-3575 4125);
DISPLAY INVISIBLE (-3575 4125);
FORCEPROP 1 LAST PATH I54
J 2
(-3248 4250);
DISPLAY 0.872340 (-3248 4250);
PAINT GREEN (-3248 4250);
DISPLAY INVISIBLE (-3248 4250);
FORCEADD TAP..1
R 2
(-3250 4300);
FORCEPROP 3 LASTPIN (-3200 4300) SIG_NAME M_H_CPU1_SA_CA<6>
J 0
(-3190 4310);
DISPLAY 0.659574 (-3190 4310);
PAINT MONO (-3190 4310);
DISPLAY INVISIBLE (-3190 4310);
FORCEPROP 1 LASTPIN (-3200 4300) BN 6
J 2
(-3188 4308);
DISPLAY 0.680851 (-3188 4308);
PAINT GREEN (-3188 4308);
FORCEPROP 2 LAST CDS_LIB standard
J 0
(-3250 4300);
DISPLAY INVISIBLE (-3250 4300);
FORCEPROP 1 LAST BODY_TYPE PLUMBING
J 2
(-3250 4350);
DISPLAY 0.872340 (-3250 4350);
PAINT GREEN (-3250 4350);
DISPLAY INVISIBLE (-3250 4350);
FORCEPROP 1 LAST HDL_TAP TRUE
J 2
(-3575 4175);
DISPLAY 0.872340 (-3575 4175);
DISPLAY INVISIBLE (-3575 4175);
FORCEPROP 1 LAST PATH I55
J 2
(-3248 4300);
DISPLAY 0.872340 (-3248 4300);
PAINT GREEN (-3248 4300);
DISPLAY INVISIBLE (-3248 4300);
FORCEADD TAP..1
(-1600 1200);
FORCEPROP 3 LASTPIN (-1650 1200) SIG_NAME M_H_CPU1_SB_DQ<2>
J 0
(-1640 1210);
DISPLAY 0.659574 (-1640 1210);
PAINT MONO (-1640 1210);
DISPLAY INVISIBLE (-1640 1210);
FORCEPROP 1 LASTPIN (-1650 1200) BN 2
J 0
(-1662 1208);
DISPLAY 0.680851 (-1662 1208);
PAINT GREEN (-1662 1208);
FORCEPROP 2 LAST CDS_LIB standard
J 0
(-1600 1200);
PAINT MONO (-1600 1200);
DISPLAY INVISIBLE (-1600 1200);
FORCEPROP 1 LAST BODY_TYPE PLUMBING
J 0
(-1600 1250);
DISPLAY 0.872340 (-1600 1250);
PAINT GREEN (-1600 1250);
DISPLAY INVISIBLE (-1600 1250);
FORCEPROP 1 LAST HDL_TAP TRUE
J 0
(-1275 1075);
DISPLAY 0.872340 (-1275 1075);
DISPLAY INVISIBLE (-1275 1075);
FORCEPROP 1 LAST PATH I56
J 0
(-1602 1200);
DISPLAY 0.872340 (-1602 1200);
PAINT GREEN (-1602 1200);
DISPLAY INVISIBLE (-1602 1200);
FORCEADD TAP..1
(-1600 1100);
FORCEPROP 3 LASTPIN (-1650 1100) SIG_NAME M_H_CPU1_SB_DQ<0>
J 0
(-1640 1110);
DISPLAY 0.659574 (-1640 1110);
PAINT MONO (-1640 1110);
DISPLAY INVISIBLE (-1640 1110);
FORCEPROP 1 LASTPIN (-1650 1100) BN 0
J 0
(-1662 1108);
DISPLAY 0.680851 (-1662 1108);
PAINT GREEN (-1662 1108);
FORCEPROP 2 LAST CDS_LIB standard
J 0
(-1600 1100);
PAINT MONO (-1600 1100);
DISPLAY INVISIBLE (-1600 1100);
FORCEPROP 1 LAST BODY_TYPE PLUMBING
J 0
(-1600 1150);
DISPLAY 0.872340 (-1600 1150);
PAINT GREEN (-1600 1150);
DISPLAY INVISIBLE (-1600 1150);
FORCEPROP 1 LAST HDL_TAP TRUE
J 0
(-1275 975);
DISPLAY 0.872340 (-1275 975);
DISPLAY INVISIBLE (-1275 975);
FORCEPROP 1 LAST PATH I57
J 0
(-1602 1100);
DISPLAY 0.872340 (-1602 1100);
PAINT GREEN (-1602 1100);
DISPLAY INVISIBLE (-1602 1100);
FORCEADD TAP..1
(-1600 1150);
FORCEPROP 3 LASTPIN (-1650 1150) SIG_NAME M_H_CPU1_SB_DQ<1>
J 0
(-1640 1160);
DISPLAY 0.659574 (-1640 1160);
PAINT MONO (-1640 1160);
DISPLAY INVISIBLE (-1640 1160);
FORCEPROP 1 LASTPIN (-1650 1150) BN 1
J 0
(-1662 1158);
DISPLAY 0.680851 (-1662 1158);
PAINT GREEN (-1662 1158);
FORCEPROP 2 LAST CDS_LIB standard
J 0
(-1600 1150);
PAINT MONO (-1600 1150);
DISPLAY INVISIBLE (-1600 1150);
FORCEPROP 1 LAST BODY_TYPE PLUMBING
J 0
(-1600 1200);
DISPLAY 0.872340 (-1600 1200);
PAINT GREEN (-1600 1200);
DISPLAY INVISIBLE (-1600 1200);
FORCEPROP 1 LAST HDL_TAP TRUE
J 0
(-1275 1025);
DISPLAY 0.872340 (-1275 1025);
DISPLAY INVISIBLE (-1275 1025);
FORCEPROP 1 LAST PATH I58
J 0
(-1602 1150);
DISPLAY 0.872340 (-1602 1150);
PAINT GREEN (-1602 1150);
DISPLAY INVISIBLE (-1602 1150);
FORCEADD TAP..1
(-1600 1250);
FORCEPROP 3 LASTPIN (-1650 1250) SIG_NAME M_H_CPU1_SB_DQ<3>
J 0
(-1640 1260);
DISPLAY 0.659574 (-1640 1260);
PAINT MONO (-1640 1260);
DISPLAY INVISIBLE (-1640 1260);
FORCEPROP 1 LASTPIN (-1650 1250) BN 3
J 0
(-1662 1258);
DISPLAY 0.680851 (-1662 1258);
PAINT GREEN (-1662 1258);
FORCEPROP 2 LAST CDS_LIB standard
J 0
(-1600 1250);
PAINT MONO (-1600 1250);
DISPLAY INVISIBLE (-1600 1250);
FORCEPROP 1 LAST BODY_TYPE PLUMBING
J 0
(-1600 1300);
DISPLAY 0.872340 (-1600 1300);
PAINT GREEN (-1600 1300);
DISPLAY INVISIBLE (-1600 1300);
FORCEPROP 1 LAST HDL_TAP TRUE
J 0
(-1275 1125);
DISPLAY 0.872340 (-1275 1125);
DISPLAY INVISIBLE (-1275 1125);
FORCEPROP 1 LAST PATH I59
J 0
(-1602 1250);
DISPLAY 0.872340 (-1602 1250);
PAINT GREEN (-1602 1250);
DISPLAY INVISIBLE (-1602 1250);
FORCEADD OFFPAGE..3
R 2
(-4175 1450);
FORCEPROP 2 LAST $XR0 114 
J 0
(-4455 1450);
DISPLAY 0.638298 (-4455 1450);
PAINT MONO (-4455 1450);
FORCEPROP 2 LAST CDS_LIB standard
J 0
(-4175 1450);
PAINT MONO (-4175 1450);
DISPLAY INVISIBLE (-4175 1450);
FORCEPROP 1 LAST OFFPAGE TRUE
J 2
(-4500 1325);
DISPLAY 0.872340 (-4500 1325);
DISPLAY INVISIBLE (-4500 1325);
FORCEPROP 1 LAST COMMENT_BODY TRUE
J 2
(-4125 1350);
DISPLAY 0.872340 (-4125 1350);
PAINT GREEN (-4125 1350);
DISPLAY INVISIBLE (-4125 1350);
FORCEPROP 2 LAST PATH I6
J 0
(-4125 1525);
DISPLAY 1.021277 (-4125 1525);
DISPLAY INVISIBLE (-4125 1525);
FORCEADD TAP..1
(-1600 1300);
FORCEPROP 3 LASTPIN (-1650 1300) SIG_NAME M_H_CPU1_SB_DQ<4>
J 0
(-1640 1310);
DISPLAY 0.659574 (-1640 1310);
PAINT MONO (-1640 1310);
DISPLAY INVISIBLE (-1640 1310);
FORCEPROP 1 LASTPIN (-1650 1300) BN 4
J 0
(-1662 1308);
DISPLAY 0.680851 (-1662 1308);
PAINT GREEN (-1662 1308);
FORCEPROP 2 LAST CDS_LIB standard
J 0
(-1600 1300);
PAINT MONO (-1600 1300);
DISPLAY INVISIBLE (-1600 1300);
FORCEPROP 1 LAST BODY_TYPE PLUMBING
J 0
(-1600 1350);
DISPLAY 0.872340 (-1600 1350);
PAINT GREEN (-1600 1350);
DISPLAY INVISIBLE (-1600 1350);
FORCEPROP 1 LAST HDL_TAP TRUE
J 0
(-1275 1175);
DISPLAY 0.872340 (-1275 1175);
DISPLAY INVISIBLE (-1275 1175);
FORCEPROP 1 LAST PATH I60
J 0
(-1602 1300);
DISPLAY 0.872340 (-1602 1300);
PAINT GREEN (-1602 1300);
DISPLAY INVISIBLE (-1602 1300);
FORCEADD TAP..1
(-1600 1400);
FORCEPROP 3 LASTPIN (-1650 1400) SIG_NAME M_H_CPU1_SB_DQ<6>
J 0
(-1640 1410);
DISPLAY 0.659574 (-1640 1410);
PAINT MONO (-1640 1410);
DISPLAY INVISIBLE (-1640 1410);
FORCEPROP 1 LASTPIN (-1650 1400) BN 6
J 0
(-1662 1408);
DISPLAY 0.680851 (-1662 1408);
PAINT GREEN (-1662 1408);
FORCEPROP 2 LAST CDS_LIB standard
J 0
(-1600 1400);
PAINT MONO (-1600 1400);
DISPLAY INVISIBLE (-1600 1400);
FORCEPROP 1 LAST BODY_TYPE PLUMBING
J 0
(-1600 1450);
DISPLAY 0.872340 (-1600 1450);
PAINT GREEN (-1600 1450);
DISPLAY INVISIBLE (-1600 1450);
FORCEPROP 1 LAST HDL_TAP TRUE
J 0
(-1275 1275);
DISPLAY 0.872340 (-1275 1275);
DISPLAY INVISIBLE (-1275 1275);
FORCEPROP 1 LAST PATH I61
J 0
(-1602 1400);
DISPLAY 0.872340 (-1602 1400);
PAINT GREEN (-1602 1400);
DISPLAY INVISIBLE (-1602 1400);
FORCEADD TAP..1
(-1600 1350);
FORCEPROP 3 LASTPIN (-1650 1350) SIG_NAME M_H_CPU1_SB_DQ<5>
J 0
(-1640 1360);
DISPLAY 0.659574 (-1640 1360);
PAINT MONO (-1640 1360);
DISPLAY INVISIBLE (-1640 1360);
FORCEPROP 1 LASTPIN (-1650 1350) BN 5
J 0
(-1662 1358);
DISPLAY 0.680851 (-1662 1358);
PAINT GREEN (-1662 1358);
FORCEPROP 2 LAST CDS_LIB standard
J 0
(-1600 1350);
PAINT MONO (-1600 1350);
DISPLAY INVISIBLE (-1600 1350);
FORCEPROP 1 LAST BODY_TYPE PLUMBING
J 0
(-1600 1400);
DISPLAY 0.872340 (-1600 1400);
PAINT GREEN (-1600 1400);
DISPLAY INVISIBLE (-1600 1400);
FORCEPROP 1 LAST HDL_TAP TRUE
J 0
(-1275 1225);
DISPLAY 0.872340 (-1275 1225);
DISPLAY INVISIBLE (-1275 1225);
FORCEPROP 1 LAST PATH I62
J 0
(-1602 1350);
DISPLAY 0.872340 (-1602 1350);
PAINT GREEN (-1602 1350);
DISPLAY INVISIBLE (-1602 1350);
FORCEADD TAP..1
(-1600 1450);
FORCEPROP 3 LASTPIN (-1650 1450) SIG_NAME M_H_CPU1_SB_DQ<7>
J 0
(-1640 1460);
DISPLAY 0.659574 (-1640 1460);
PAINT MONO (-1640 1460);
DISPLAY INVISIBLE (-1640 1460);
FORCEPROP 1 LASTPIN (-1650 1450) BN 7
J 0
(-1662 1458);
DISPLAY 0.680851 (-1662 1458);
PAINT GREEN (-1662 1458);
FORCEPROP 2 LAST CDS_LIB standard
J 0
(-1600 1450);
PAINT MONO (-1600 1450);
DISPLAY INVISIBLE (-1600 1450);
FORCEPROP 1 LAST BODY_TYPE PLUMBING
J 0
(-1600 1500);
DISPLAY 0.872340 (-1600 1500);
PAINT GREEN (-1600 1500);
DISPLAY INVISIBLE (-1600 1500);
FORCEPROP 1 LAST HDL_TAP TRUE
J 0
(-1275 1325);
DISPLAY 0.872340 (-1275 1325);
DISPLAY INVISIBLE (-1275 1325);
FORCEPROP 1 LAST PATH I63
J 0
(-1602 1450);
DISPLAY 0.872340 (-1602 1450);
PAINT GREEN (-1602 1450);
DISPLAY INVISIBLE (-1602 1450);
FORCEADD TAP..1
(-1600 1500);
FORCEPROP 3 LASTPIN (-1650 1500) SIG_NAME M_H_CPU1_SB_DQ<8>
J 0
(-1640 1510);
DISPLAY 0.659574 (-1640 1510);
PAINT MONO (-1640 1510);
DISPLAY INVISIBLE (-1640 1510);
FORCEPROP 1 LASTPIN (-1650 1500) BN 8
J 0
(-1662 1508);
DISPLAY 0.680851 (-1662 1508);
PAINT GREEN (-1662 1508);
FORCEPROP 2 LAST CDS_LIB standard
J 0
(-1600 1500);
PAINT MONO (-1600 1500);
DISPLAY INVISIBLE (-1600 1500);
FORCEPROP 1 LAST BODY_TYPE PLUMBING
J 0
(-1600 1550);
DISPLAY 0.872340 (-1600 1550);
PAINT GREEN (-1600 1550);
DISPLAY INVISIBLE (-1600 1550);
FORCEPROP 1 LAST HDL_TAP TRUE
J 0
(-1275 1375);
DISPLAY 0.872340 (-1275 1375);
DISPLAY INVISIBLE (-1275 1375);
FORCEPROP 1 LAST PATH I64
J 0
(-1602 1500);
DISPLAY 0.872340 (-1602 1500);
PAINT GREEN (-1602 1500);
DISPLAY INVISIBLE (-1602 1500);
FORCEADD TAP..1
(-1600 1550);
FORCEPROP 3 LASTPIN (-1650 1550) SIG_NAME M_H_CPU1_SB_DQ<9>
J 0
(-1640 1560);
DISPLAY 0.659574 (-1640 1560);
PAINT MONO (-1640 1560);
DISPLAY INVISIBLE (-1640 1560);
FORCEPROP 1 LASTPIN (-1650 1550) BN 9
J 0
(-1662 1558);
DISPLAY 0.680851 (-1662 1558);
PAINT GREEN (-1662 1558);
FORCEPROP 2 LAST CDS_LIB standard
J 0
(-1600 1550);
PAINT MONO (-1600 1550);
DISPLAY INVISIBLE (-1600 1550);
FORCEPROP 1 LAST BODY_TYPE PLUMBING
J 0
(-1600 1600);
DISPLAY 0.872340 (-1600 1600);
PAINT GREEN (-1600 1600);
DISPLAY INVISIBLE (-1600 1600);
FORCEPROP 1 LAST HDL_TAP TRUE
J 0
(-1275 1425);
DISPLAY 0.872340 (-1275 1425);
DISPLAY INVISIBLE (-1275 1425);
FORCEPROP 1 LAST PATH I65
J 0
(-1602 1550);
DISPLAY 0.872340 (-1602 1550);
PAINT GREEN (-1602 1550);
DISPLAY INVISIBLE (-1602 1550);
FORCEADD TAP..1
(-1600 1600);
FORCEPROP 3 LASTPIN (-1650 1600) SIG_NAME M_H_CPU1_SB_DQ<10>
J 0
(-1640 1610);
DISPLAY 0.659574 (-1640 1610);
PAINT MONO (-1640 1610);
DISPLAY INVISIBLE (-1640 1610);
FORCEPROP 1 LASTPIN (-1650 1600) BN 10
J 0
(-1662 1608);
DISPLAY 0.680851 (-1662 1608);
PAINT GREEN (-1662 1608);
FORCEPROP 2 LAST CDS_LIB standard
J 0
(-1600 1600);
PAINT MONO (-1600 1600);
DISPLAY INVISIBLE (-1600 1600);
FORCEPROP 1 LAST BODY_TYPE PLUMBING
J 0
(-1600 1650);
DISPLAY 0.872340 (-1600 1650);
PAINT GREEN (-1600 1650);
DISPLAY INVISIBLE (-1600 1650);
FORCEPROP 1 LAST HDL_TAP TRUE
J 0
(-1275 1475);
DISPLAY 0.872340 (-1275 1475);
DISPLAY INVISIBLE (-1275 1475);
FORCEPROP 1 LAST PATH I66
J 0
(-1602 1600);
DISPLAY 0.872340 (-1602 1600);
PAINT GREEN (-1602 1600);
DISPLAY INVISIBLE (-1602 1600);
FORCEADD TAP..1
(-1600 1650);
FORCEPROP 3 LASTPIN (-1650 1650) SIG_NAME M_H_CPU1_SB_DQ<11>
J 0
(-1640 1660);
DISPLAY 0.659574 (-1640 1660);
PAINT MONO (-1640 1660);
DISPLAY INVISIBLE (-1640 1660);
FORCEPROP 1 LASTPIN (-1650 1650) BN 11
J 0
(-1662 1658);
DISPLAY 0.680851 (-1662 1658);
PAINT GREEN (-1662 1658);
FORCEPROP 2 LAST CDS_LIB standard
J 0
(-1600 1650);
PAINT MONO (-1600 1650);
DISPLAY INVISIBLE (-1600 1650);
FORCEPROP 1 LAST BODY_TYPE PLUMBING
J 0
(-1600 1700);
DISPLAY 0.872340 (-1600 1700);
PAINT GREEN (-1600 1700);
DISPLAY INVISIBLE (-1600 1700);
FORCEPROP 1 LAST HDL_TAP TRUE
J 0
(-1275 1525);
DISPLAY 0.872340 (-1275 1525);
DISPLAY INVISIBLE (-1275 1525);
FORCEPROP 1 LAST PATH I67
J 0
(-1602 1650);
DISPLAY 0.872340 (-1602 1650);
PAINT GREEN (-1602 1650);
DISPLAY INVISIBLE (-1602 1650);
FORCEADD TAP..1
(-1600 1700);
FORCEPROP 3 LASTPIN (-1650 1700) SIG_NAME M_H_CPU1_SB_DQ<12>
J 0
(-1640 1710);
DISPLAY 0.659574 (-1640 1710);
PAINT MONO (-1640 1710);
DISPLAY INVISIBLE (-1640 1710);
FORCEPROP 1 LASTPIN (-1650 1700) BN 12
J 0
(-1662 1708);
DISPLAY 0.680851 (-1662 1708);
PAINT GREEN (-1662 1708);
FORCEPROP 2 LAST CDS_LIB standard
J 0
(-1600 1700);
PAINT MONO (-1600 1700);
DISPLAY INVISIBLE (-1600 1700);
FORCEPROP 1 LAST BODY_TYPE PLUMBING
J 0
(-1600 1750);
DISPLAY 0.872340 (-1600 1750);
PAINT GREEN (-1600 1750);
DISPLAY INVISIBLE (-1600 1750);
FORCEPROP 1 LAST HDL_TAP TRUE
J 0
(-1275 1575);
DISPLAY 0.872340 (-1275 1575);
DISPLAY INVISIBLE (-1275 1575);
FORCEPROP 1 LAST PATH I68
J 0
(-1602 1700);
DISPLAY 0.872340 (-1602 1700);
PAINT GREEN (-1602 1700);
DISPLAY INVISIBLE (-1602 1700);
FORCEADD TAP..1
(-1600 1750);
FORCEPROP 3 LASTPIN (-1650 1750) SIG_NAME M_H_CPU1_SB_DQ<13>
J 0
(-1640 1760);
DISPLAY 0.659574 (-1640 1760);
PAINT MONO (-1640 1760);
DISPLAY INVISIBLE (-1640 1760);
FORCEPROP 1 LASTPIN (-1650 1750) BN 13
J 0
(-1662 1758);
DISPLAY 0.680851 (-1662 1758);
PAINT GREEN (-1662 1758);
FORCEPROP 2 LAST CDS_LIB standard
J 0
(-1600 1750);
PAINT MONO (-1600 1750);
DISPLAY INVISIBLE (-1600 1750);
FORCEPROP 1 LAST BODY_TYPE PLUMBING
J 0
(-1600 1800);
DISPLAY 0.872340 (-1600 1800);
PAINT GREEN (-1600 1800);
DISPLAY INVISIBLE (-1600 1800);
FORCEPROP 1 LAST HDL_TAP TRUE
J 0
(-1275 1625);
DISPLAY 0.872340 (-1275 1625);
DISPLAY INVISIBLE (-1275 1625);
FORCEPROP 1 LAST PATH I69
J 0
(-1602 1750);
DISPLAY 0.872340 (-1602 1750);
PAINT GREEN (-1602 1750);
DISPLAY INVISIBLE (-1602 1750);
FORCEADD TAP..1
(-1600 1800);
FORCEPROP 3 LASTPIN (-1650 1800) SIG_NAME M_H_CPU1_SB_DQ<14>
J 0
(-1640 1810);
DISPLAY 0.659574 (-1640 1810);
PAINT MONO (-1640 1810);
DISPLAY INVISIBLE (-1640 1810);
FORCEPROP 1 LASTPIN (-1650 1800) BN 14
J 0
(-1662 1808);
DISPLAY 0.680851 (-1662 1808);
PAINT GREEN (-1662 1808);
FORCEPROP 2 LAST CDS_LIB standard
J 0
(-1600 1800);
PAINT MONO (-1600 1800);
DISPLAY INVISIBLE (-1600 1800);
FORCEPROP 1 LAST BODY_TYPE PLUMBING
J 0
(-1600 1850);
DISPLAY 0.872340 (-1600 1850);
PAINT GREEN (-1600 1850);
DISPLAY INVISIBLE (-1600 1850);
FORCEPROP 1 LAST HDL_TAP TRUE
J 0
(-1275 1675);
DISPLAY 0.872340 (-1275 1675);
DISPLAY INVISIBLE (-1275 1675);
FORCEPROP 1 LAST PATH I70
J 0
(-1602 1800);
DISPLAY 0.872340 (-1602 1800);
PAINT GREEN (-1602 1800);
DISPLAY INVISIBLE (-1602 1800);
FORCEADD TAP..1
(-1600 1850);
FORCEPROP 3 LASTPIN (-1650 1850) SIG_NAME M_H_CPU1_SB_DQ<15>
J 0
(-1640 1860);
DISPLAY 0.659574 (-1640 1860);
PAINT MONO (-1640 1860);
DISPLAY INVISIBLE (-1640 1860);
FORCEPROP 1 LASTPIN (-1650 1850) BN 15
J 0
(-1662 1858);
DISPLAY 0.680851 (-1662 1858);
PAINT GREEN (-1662 1858);
FORCEPROP 2 LAST CDS_LIB standard
J 0
(-1600 1850);
PAINT MONO (-1600 1850);
DISPLAY INVISIBLE (-1600 1850);
FORCEPROP 1 LAST BODY_TYPE PLUMBING
J 0
(-1600 1900);
DISPLAY 0.872340 (-1600 1900);
PAINT GREEN (-1600 1900);
DISPLAY INVISIBLE (-1600 1900);
FORCEPROP 1 LAST HDL_TAP TRUE
J 0
(-1275 1725);
DISPLAY 0.872340 (-1275 1725);
DISPLAY INVISIBLE (-1275 1725);
FORCEPROP 1 LAST PATH I71
J 0
(-1602 1850);
DISPLAY 0.872340 (-1602 1850);
PAINT GREEN (-1602 1850);
DISPLAY INVISIBLE (-1602 1850);
FORCEADD TAP..1
(-1600 1900);
FORCEPROP 3 LASTPIN (-1650 1900) SIG_NAME M_H_CPU1_SB_DQ<16>
J 0
(-1640 1910);
DISPLAY 0.659574 (-1640 1910);
PAINT MONO (-1640 1910);
DISPLAY INVISIBLE (-1640 1910);
FORCEPROP 1 LASTPIN (-1650 1900) BN 16
J 0
(-1662 1908);
DISPLAY 0.680851 (-1662 1908);
PAINT GREEN (-1662 1908);
FORCEPROP 2 LAST CDS_LIB standard
J 0
(-1600 1900);
PAINT MONO (-1600 1900);
DISPLAY INVISIBLE (-1600 1900);
FORCEPROP 1 LAST BODY_TYPE PLUMBING
J 0
(-1600 1950);
DISPLAY 0.872340 (-1600 1950);
PAINT GREEN (-1600 1950);
DISPLAY INVISIBLE (-1600 1950);
FORCEPROP 1 LAST HDL_TAP TRUE
J 0
(-1275 1775);
DISPLAY 0.872340 (-1275 1775);
DISPLAY INVISIBLE (-1275 1775);
FORCEPROP 1 LAST PATH I72
J 0
(-1602 1900);
DISPLAY 0.872340 (-1602 1900);
PAINT GREEN (-1602 1900);
DISPLAY INVISIBLE (-1602 1900);
FORCEADD TAP..1
(-1600 1950);
FORCEPROP 3 LASTPIN (-1650 1950) SIG_NAME M_H_CPU1_SB_DQ<17>
J 0
(-1640 1960);
DISPLAY 0.659574 (-1640 1960);
PAINT MONO (-1640 1960);
DISPLAY INVISIBLE (-1640 1960);
FORCEPROP 1 LASTPIN (-1650 1950) BN 17
J 0
(-1662 1958);
DISPLAY 0.680851 (-1662 1958);
PAINT GREEN (-1662 1958);
FORCEPROP 2 LAST CDS_LIB standard
J 0
(-1600 1950);
PAINT MONO (-1600 1950);
DISPLAY INVISIBLE (-1600 1950);
FORCEPROP 1 LAST BODY_TYPE PLUMBING
J 0
(-1600 2000);
DISPLAY 0.872340 (-1600 2000);
PAINT GREEN (-1600 2000);
DISPLAY INVISIBLE (-1600 2000);
FORCEPROP 1 LAST HDL_TAP TRUE
J 0
(-1275 1825);
DISPLAY 0.872340 (-1275 1825);
DISPLAY INVISIBLE (-1275 1825);
FORCEPROP 1 LAST PATH I73
J 0
(-1602 1950);
DISPLAY 0.872340 (-1602 1950);
PAINT GREEN (-1602 1950);
DISPLAY INVISIBLE (-1602 1950);
FORCEADD TAP..1
(-1600 2050);
FORCEPROP 3 LASTPIN (-1650 2050) SIG_NAME M_H_CPU1_SB_DQ<19>
J 0
(-1640 2060);
DISPLAY 0.659574 (-1640 2060);
PAINT MONO (-1640 2060);
DISPLAY INVISIBLE (-1640 2060);
FORCEPROP 1 LASTPIN (-1650 2050) BN 19
J 0
(-1662 2058);
DISPLAY 0.680851 (-1662 2058);
PAINT GREEN (-1662 2058);
FORCEPROP 2 LAST CDS_LIB standard
J 0
(-1600 2050);
PAINT MONO (-1600 2050);
DISPLAY INVISIBLE (-1600 2050);
FORCEPROP 1 LAST BODY_TYPE PLUMBING
J 0
(-1600 2100);
DISPLAY 0.872340 (-1600 2100);
PAINT GREEN (-1600 2100);
DISPLAY INVISIBLE (-1600 2100);
FORCEPROP 1 LAST HDL_TAP TRUE
J 0
(-1275 1925);
DISPLAY 0.872340 (-1275 1925);
DISPLAY INVISIBLE (-1275 1925);
FORCEPROP 1 LAST PATH I74
J 0
(-1602 2050);
DISPLAY 0.872340 (-1602 2050);
PAINT GREEN (-1602 2050);
DISPLAY INVISIBLE (-1602 2050);
FORCEADD TAP..1
(-1600 2000);
FORCEPROP 3 LASTPIN (-1650 2000) SIG_NAME M_H_CPU1_SB_DQ<18>
J 0
(-1640 2010);
DISPLAY 0.659574 (-1640 2010);
PAINT MONO (-1640 2010);
DISPLAY INVISIBLE (-1640 2010);
FORCEPROP 1 LASTPIN (-1650 2000) BN 18
J 0
(-1662 2008);
DISPLAY 0.680851 (-1662 2008);
PAINT GREEN (-1662 2008);
FORCEPROP 2 LAST CDS_LIB standard
J 0
(-1600 2000);
PAINT MONO (-1600 2000);
DISPLAY INVISIBLE (-1600 2000);
FORCEPROP 1 LAST BODY_TYPE PLUMBING
J 0
(-1600 2050);
DISPLAY 0.872340 (-1600 2050);
PAINT GREEN (-1600 2050);
DISPLAY INVISIBLE (-1600 2050);
FORCEPROP 1 LAST HDL_TAP TRUE
J 0
(-1275 1875);
DISPLAY 0.872340 (-1275 1875);
DISPLAY INVISIBLE (-1275 1875);
FORCEPROP 1 LAST PATH I75
J 0
(-1602 2000);
DISPLAY 0.872340 (-1602 2000);
PAINT GREEN (-1602 2000);
DISPLAY INVISIBLE (-1602 2000);
FORCEADD TAP..1
(-1600 2100);
FORCEPROP 3 LASTPIN (-1650 2100) SIG_NAME M_H_CPU1_SB_DQ<20>
J 0
(-1640 2110);
DISPLAY 0.659574 (-1640 2110);
PAINT MONO (-1640 2110);
DISPLAY INVISIBLE (-1640 2110);
FORCEPROP 1 LASTPIN (-1650 2100) BN 20
J 0
(-1662 2108);
DISPLAY 0.680851 (-1662 2108);
PAINT GREEN (-1662 2108);
FORCEPROP 2 LAST CDS_LIB standard
J 0
(-1600 2100);
PAINT MONO (-1600 2100);
DISPLAY INVISIBLE (-1600 2100);
FORCEPROP 1 LAST BODY_TYPE PLUMBING
J 0
(-1600 2150);
DISPLAY 0.872340 (-1600 2150);
PAINT GREEN (-1600 2150);
DISPLAY INVISIBLE (-1600 2150);
FORCEPROP 1 LAST HDL_TAP TRUE
J 0
(-1275 1975);
DISPLAY 0.872340 (-1275 1975);
DISPLAY INVISIBLE (-1275 1975);
FORCEPROP 1 LAST PATH I76
J 0
(-1602 2100);
DISPLAY 0.872340 (-1602 2100);
PAINT GREEN (-1602 2100);
DISPLAY INVISIBLE (-1602 2100);
FORCEADD TAP..1
(-1600 2200);
FORCEPROP 3 LASTPIN (-1650 2200) SIG_NAME M_H_CPU1_SB_DQ<22>
J 0
(-1640 2210);
DISPLAY 0.659574 (-1640 2210);
PAINT MONO (-1640 2210);
DISPLAY INVISIBLE (-1640 2210);
FORCEPROP 1 LASTPIN (-1650 2200) BN 22
J 0
(-1662 2208);
DISPLAY 0.680851 (-1662 2208);
PAINT GREEN (-1662 2208);
FORCEPROP 2 LAST CDS_LIB standard
J 0
(-1600 2200);
DISPLAY INVISIBLE (-1600 2200);
FORCEPROP 1 LAST BODY_TYPE PLUMBING
J 0
(-1600 2250);
DISPLAY 0.872340 (-1600 2250);
PAINT GREEN (-1600 2250);
DISPLAY INVISIBLE (-1600 2250);
FORCEPROP 1 LAST HDL_TAP TRUE
J 0
(-1275 2075);
DISPLAY 0.872340 (-1275 2075);
DISPLAY INVISIBLE (-1275 2075);
FORCEPROP 1 LAST PATH I77
J 0
(-1602 2200);
DISPLAY 0.872340 (-1602 2200);
PAINT GREEN (-1602 2200);
DISPLAY INVISIBLE (-1602 2200);
FORCEADD TAP..1
(-1600 2150);
FORCEPROP 3 LASTPIN (-1650 2150) SIG_NAME M_H_CPU1_SB_DQ<21>
J 0
(-1640 2160);
DISPLAY 0.659574 (-1640 2160);
PAINT MONO (-1640 2160);
DISPLAY INVISIBLE (-1640 2160);
FORCEPROP 1 LASTPIN (-1650 2150) BN 21
J 0
(-1662 2158);
DISPLAY 0.680851 (-1662 2158);
PAINT GREEN (-1662 2158);
FORCEPROP 2 LAST CDS_LIB standard
J 0
(-1600 2150);
PAINT MONO (-1600 2150);
DISPLAY INVISIBLE (-1600 2150);
FORCEPROP 1 LAST BODY_TYPE PLUMBING
J 0
(-1600 2200);
DISPLAY 0.872340 (-1600 2200);
PAINT GREEN (-1600 2200);
DISPLAY INVISIBLE (-1600 2200);
FORCEPROP 1 LAST HDL_TAP TRUE
J 0
(-1275 2025);
DISPLAY 0.872340 (-1275 2025);
DISPLAY INVISIBLE (-1275 2025);
FORCEPROP 1 LAST PATH I78
J 0
(-1602 2150);
DISPLAY 0.872340 (-1602 2150);
PAINT GREEN (-1602 2150);
DISPLAY INVISIBLE (-1602 2150);
FORCEADD TAP..1
(-1600 2250);
FORCEPROP 3 LASTPIN (-1650 2250) SIG_NAME M_H_CPU1_SB_DQ<23>
J 0
(-1640 2260);
DISPLAY 0.659574 (-1640 2260);
PAINT MONO (-1640 2260);
DISPLAY INVISIBLE (-1640 2260);
FORCEPROP 1 LASTPIN (-1650 2250) BN 23
J 0
(-1662 2258);
DISPLAY 0.680851 (-1662 2258);
PAINT GREEN (-1662 2258);
FORCEPROP 2 LAST CDS_LIB standard
J 0
(-1600 2250);
DISPLAY INVISIBLE (-1600 2250);
FORCEPROP 1 LAST BODY_TYPE PLUMBING
J 0
(-1600 2300);
DISPLAY 0.872340 (-1600 2300);
PAINT GREEN (-1600 2300);
DISPLAY INVISIBLE (-1600 2300);
FORCEPROP 1 LAST HDL_TAP TRUE
J 0
(-1275 2125);
DISPLAY 0.872340 (-1275 2125);
DISPLAY INVISIBLE (-1275 2125);
FORCEPROP 1 LAST PATH I79
J 0
(-1602 2250);
DISPLAY 0.872340 (-1602 2250);
PAINT GREEN (-1602 2250);
DISPLAY INVISIBLE (-1602 2250);
FORCEADD OFFPAGE..1
(-4125 1750);
FORCEPROP 2 LAST $XR7 113 
J 0
(-4647 1786);
DISPLAY 0.638298 (-4647 1786);
PAINT MONO (-4647 1786);
FORCEPROP 2 LAST $XR6 111 
J 0
(-4527 1786);
DISPLAY 0.638298 (-4527 1786);
PAINT MONO (-4527 1786);
FORCEPROP 2 LAST $XR5 110 
J 0
(-4647 1714);
DISPLAY 0.638298 (-4647 1714);
PAINT MONO (-4647 1714);
FORCEPROP 2 LAST $XR4 109 
J 0
(-4527 1714);
DISPLAY 0.638298 (-4527 1714);
PAINT MONO (-4527 1714);
FORCEPROP 2 LAST $XR3 108 
J 0
(-4407 1714);
DISPLAY 0.638298 (-4407 1714);
PAINT MONO (-4407 1714);
FORCEPROP 2 LAST $XR2 107 
J 0
(-4647 1750);
DISPLAY 0.638298 (-4647 1750);
PAINT MONO (-4647 1750);
FORCEPROP 2 LAST $XR1 106 
J 0
(-4527 1750);
DISPLAY 0.638298 (-4527 1750);
PAINT MONO (-4527 1750);
FORCEPROP 2 LAST $XR0 230 
J 0
(-4407 1750);
DISPLAY 0.638298 (-4407 1750);
PAINT MONO (-4407 1750);
FORCEPROP 2 LAST CDS_LIB standard
J 0
(-4125 1750);
PAINT MONO (-4125 1750);
DISPLAY INVISIBLE (-4125 1750);
FORCEPROP 1 LAST OFFPAGE TRUE
J 0
(-3800 1625);
DISPLAY 0.872340 (-3800 1625);
DISPLAY INVISIBLE (-3800 1625);
FORCEPROP 1 LAST COMMENT_BODY TRUE
J 0
(-4000 1650);
DISPLAY 0.872340 (-4000 1650);
PAINT GREEN (-4000 1650);
DISPLAY INVISIBLE (-4000 1650);
FORCEPROP 2 LAST PATH I8
J 0
(-4075 1825);
DISPLAY 1.021277 (-4075 1825);
DISPLAY INVISIBLE (-4075 1825);
FORCEADD TAP..1
(-1600 2300);
FORCEPROP 3 LASTPIN (-1650 2300) SIG_NAME M_H_CPU1_SB_DQ<24>
J 0
(-1640 2310);
DISPLAY 0.659574 (-1640 2310);
PAINT MONO (-1640 2310);
DISPLAY INVISIBLE (-1640 2310);
FORCEPROP 1 LASTPIN (-1650 2300) BN 24
J 0
(-1662 2308);
DISPLAY 0.680851 (-1662 2308);
PAINT GREEN (-1662 2308);
FORCEPROP 2 LAST CDS_LIB standard
J 0
(-1600 2300);
DISPLAY INVISIBLE (-1600 2300);
FORCEPROP 1 LAST BODY_TYPE PLUMBING
J 0
(-1600 2350);
DISPLAY 0.872340 (-1600 2350);
PAINT GREEN (-1600 2350);
DISPLAY INVISIBLE (-1600 2350);
FORCEPROP 1 LAST HDL_TAP TRUE
J 0
(-1275 2175);
DISPLAY 0.872340 (-1275 2175);
DISPLAY INVISIBLE (-1275 2175);
FORCEPROP 1 LAST PATH I80
J 0
(-1602 2300);
DISPLAY 0.872340 (-1602 2300);
PAINT GREEN (-1602 2300);
DISPLAY INVISIBLE (-1602 2300);
FORCEADD TAP..1
(-1600 2350);
FORCEPROP 3 LASTPIN (-1650 2350) SIG_NAME M_H_CPU1_SB_DQ<25>
J 0
(-1640 2360);
DISPLAY 0.659574 (-1640 2360);
PAINT MONO (-1640 2360);
DISPLAY INVISIBLE (-1640 2360);
FORCEPROP 1 LASTPIN (-1650 2350) BN 25
J 0
(-1662 2358);
DISPLAY 0.680851 (-1662 2358);
PAINT GREEN (-1662 2358);
FORCEPROP 2 LAST CDS_LIB standard
J 0
(-1600 2350);
DISPLAY INVISIBLE (-1600 2350);
FORCEPROP 1 LAST BODY_TYPE PLUMBING
J 0
(-1600 2400);
DISPLAY 0.872340 (-1600 2400);
PAINT GREEN (-1600 2400);
DISPLAY INVISIBLE (-1600 2400);
FORCEPROP 1 LAST HDL_TAP TRUE
J 0
(-1275 2225);
DISPLAY 0.872340 (-1275 2225);
DISPLAY INVISIBLE (-1275 2225);
FORCEPROP 1 LAST PATH I81
J 0
(-1602 2350);
DISPLAY 0.872340 (-1602 2350);
PAINT GREEN (-1602 2350);
DISPLAY INVISIBLE (-1602 2350);
FORCEADD TAP..1
(-1600 2450);
FORCEPROP 3 LASTPIN (-1650 2450) SIG_NAME M_H_CPU1_SB_DQ<27>
J 0
(-1640 2460);
DISPLAY 0.659574 (-1640 2460);
PAINT MONO (-1640 2460);
DISPLAY INVISIBLE (-1640 2460);
FORCEPROP 1 LASTPIN (-1650 2450) BN 27
J 0
(-1662 2458);
DISPLAY 0.680851 (-1662 2458);
PAINT GREEN (-1662 2458);
FORCEPROP 2 LAST CDS_LIB standard
J 0
(-1600 2450);
DISPLAY INVISIBLE (-1600 2450);
FORCEPROP 1 LAST BODY_TYPE PLUMBING
J 0
(-1600 2500);
DISPLAY 0.872340 (-1600 2500);
PAINT GREEN (-1600 2500);
DISPLAY INVISIBLE (-1600 2500);
FORCEPROP 1 LAST HDL_TAP TRUE
J 0
(-1275 2325);
DISPLAY 0.872340 (-1275 2325);
DISPLAY INVISIBLE (-1275 2325);
FORCEPROP 1 LAST PATH I82
J 0
(-1602 2450);
DISPLAY 0.872340 (-1602 2450);
PAINT GREEN (-1602 2450);
DISPLAY INVISIBLE (-1602 2450);
FORCEADD TAP..1
(-1600 2400);
FORCEPROP 3 LASTPIN (-1650 2400) SIG_NAME M_H_CPU1_SB_DQ<26>
J 0
(-1640 2410);
DISPLAY 0.659574 (-1640 2410);
PAINT MONO (-1640 2410);
DISPLAY INVISIBLE (-1640 2410);
FORCEPROP 1 LASTPIN (-1650 2400) BN 26
J 0
(-1662 2408);
DISPLAY 0.680851 (-1662 2408);
PAINT GREEN (-1662 2408);
FORCEPROP 2 LAST CDS_LIB standard
J 0
(-1600 2400);
DISPLAY INVISIBLE (-1600 2400);
FORCEPROP 1 LAST BODY_TYPE PLUMBING
J 0
(-1600 2450);
DISPLAY 0.872340 (-1600 2450);
PAINT GREEN (-1600 2450);
DISPLAY INVISIBLE (-1600 2450);
FORCEPROP 1 LAST HDL_TAP TRUE
J 0
(-1275 2275);
DISPLAY 0.872340 (-1275 2275);
DISPLAY INVISIBLE (-1275 2275);
FORCEPROP 1 LAST PATH I83
J 0
(-1602 2400);
DISPLAY 0.872340 (-1602 2400);
PAINT GREEN (-1602 2400);
DISPLAY INVISIBLE (-1602 2400);
FORCEADD TAP..1
(-1600 2500);
FORCEPROP 3 LASTPIN (-1650 2500) SIG_NAME M_H_CPU1_SB_DQ<28>
J 0
(-1640 2510);
DISPLAY 0.659574 (-1640 2510);
PAINT MONO (-1640 2510);
DISPLAY INVISIBLE (-1640 2510);
FORCEPROP 1 LASTPIN (-1650 2500) BN 28
J 0
(-1662 2508);
DISPLAY 0.680851 (-1662 2508);
PAINT GREEN (-1662 2508);
FORCEPROP 2 LAST CDS_LIB standard
J 0
(-1600 2500);
DISPLAY INVISIBLE (-1600 2500);
FORCEPROP 1 LAST BODY_TYPE PLUMBING
J 0
(-1600 2550);
DISPLAY 0.872340 (-1600 2550);
PAINT GREEN (-1600 2550);
DISPLAY INVISIBLE (-1600 2550);
FORCEPROP 1 LAST HDL_TAP TRUE
J 0
(-1275 2375);
DISPLAY 0.872340 (-1275 2375);
DISPLAY INVISIBLE (-1275 2375);
FORCEPROP 1 LAST PATH I84
J 0
(-1602 2500);
DISPLAY 0.872340 (-1602 2500);
PAINT GREEN (-1602 2500);
DISPLAY INVISIBLE (-1602 2500);
FORCEADD TAP..1
(-1600 2550);
FORCEPROP 3 LASTPIN (-1650 2550) SIG_NAME M_H_CPU1_SB_DQ<29>
J 0
(-1640 2560);
DISPLAY 0.659574 (-1640 2560);
PAINT MONO (-1640 2560);
DISPLAY INVISIBLE (-1640 2560);
FORCEPROP 1 LASTPIN (-1650 2550) BN 29
J 0
(-1662 2558);
DISPLAY 0.680851 (-1662 2558);
PAINT GREEN (-1662 2558);
FORCEPROP 2 LAST CDS_LIB standard
J 0
(-1600 2550);
DISPLAY INVISIBLE (-1600 2550);
FORCEPROP 1 LAST BODY_TYPE PLUMBING
J 0
(-1600 2600);
DISPLAY 0.872340 (-1600 2600);
PAINT GREEN (-1600 2600);
DISPLAY INVISIBLE (-1600 2600);
FORCEPROP 1 LAST HDL_TAP TRUE
J 0
(-1275 2425);
DISPLAY 0.872340 (-1275 2425);
DISPLAY INVISIBLE (-1275 2425);
FORCEPROP 1 LAST PATH I85
J 0
(-1602 2550);
DISPLAY 0.872340 (-1602 2550);
PAINT GREEN (-1602 2550);
DISPLAY INVISIBLE (-1602 2550);
FORCEADD TAP..1
(-1600 2600);
FORCEPROP 3 LASTPIN (-1650 2600) SIG_NAME M_H_CPU1_SB_DQ<30>
J 0
(-1640 2610);
DISPLAY 0.659574 (-1640 2610);
PAINT MONO (-1640 2610);
DISPLAY INVISIBLE (-1640 2610);
FORCEPROP 1 LASTPIN (-1650 2600) BN 30
J 0
(-1662 2608);
DISPLAY 0.680851 (-1662 2608);
PAINT GREEN (-1662 2608);
FORCEPROP 2 LAST CDS_LIB standard
J 0
(-1600 2600);
DISPLAY INVISIBLE (-1600 2600);
FORCEPROP 1 LAST BODY_TYPE PLUMBING
J 0
(-1600 2650);
DISPLAY 0.872340 (-1600 2650);
PAINT GREEN (-1600 2650);
DISPLAY INVISIBLE (-1600 2650);
FORCEPROP 1 LAST HDL_TAP TRUE
J 0
(-1275 2475);
DISPLAY 0.872340 (-1275 2475);
DISPLAY INVISIBLE (-1275 2475);
FORCEPROP 1 LAST PATH I86
J 0
(-1602 2600);
DISPLAY 0.872340 (-1602 2600);
PAINT GREEN (-1602 2600);
DISPLAY INVISIBLE (-1602 2600);
FORCEADD TAP..1
(-1600 2850);
FORCEPROP 3 LASTPIN (-1650 2850) SIG_NAME M_H_CPU1_SA_DQ<2>
J 0
(-1640 2860);
DISPLAY 0.659574 (-1640 2860);
PAINT MONO (-1640 2860);
DISPLAY INVISIBLE (-1640 2860);
FORCEPROP 1 LASTPIN (-1650 2850) BN 2
J 0
(-1662 2858);
DISPLAY 0.680851 (-1662 2858);
PAINT GREEN (-1662 2858);
FORCEPROP 2 LAST CDS_LIB standard
J 0
(-1600 2850);
PAINT MONO (-1600 2850);
DISPLAY INVISIBLE (-1600 2850);
FORCEPROP 1 LAST BODY_TYPE PLUMBING
J 0
(-1600 2900);
DISPLAY 0.872340 (-1600 2900);
PAINT GREEN (-1600 2900);
DISPLAY INVISIBLE (-1600 2900);
FORCEPROP 1 LAST HDL_TAP TRUE
J 0
(-1275 2725);
DISPLAY 0.872340 (-1275 2725);
DISPLAY INVISIBLE (-1275 2725);
FORCEPROP 1 LAST PATH I87
J 0
(-1602 2850);
DISPLAY 0.872340 (-1602 2850);
PAINT GREEN (-1602 2850);
DISPLAY INVISIBLE (-1602 2850);
FORCEADD TAP..1
(-1600 2750);
FORCEPROP 3 LASTPIN (-1650 2750) SIG_NAME M_H_CPU1_SA_DQ<0>
J 0
(-1640 2760);
DISPLAY 0.659574 (-1640 2760);
PAINT MONO (-1640 2760);
DISPLAY INVISIBLE (-1640 2760);
FORCEPROP 1 LASTPIN (-1650 2750) BN 0
J 0
(-1662 2758);
DISPLAY 0.680851 (-1662 2758);
PAINT GREEN (-1662 2758);
FORCEPROP 2 LAST CDS_LIB standard
J 0
(-1600 2750);
PAINT MONO (-1600 2750);
DISPLAY INVISIBLE (-1600 2750);
FORCEPROP 1 LAST BODY_TYPE PLUMBING
J 0
(-1600 2800);
DISPLAY 0.872340 (-1600 2800);
PAINT GREEN (-1600 2800);
DISPLAY INVISIBLE (-1600 2800);
FORCEPROP 1 LAST HDL_TAP TRUE
J 0
(-1275 2625);
DISPLAY 0.872340 (-1275 2625);
DISPLAY INVISIBLE (-1275 2625);
FORCEPROP 1 LAST PATH I88
J 0
(-1602 2750);
DISPLAY 0.872340 (-1602 2750);
PAINT GREEN (-1602 2750);
DISPLAY INVISIBLE (-1602 2750);
FORCEADD TAP..1
(-1600 2650);
FORCEPROP 3 LASTPIN (-1650 2650) SIG_NAME M_H_CPU1_SB_DQ<31>
J 0
(-1640 2660);
DISPLAY 0.659574 (-1640 2660);
PAINT MONO (-1640 2660);
DISPLAY INVISIBLE (-1640 2660);
FORCEPROP 1 LASTPIN (-1650 2650) BN 31
J 0
(-1662 2658);
DISPLAY 0.680851 (-1662 2658);
PAINT GREEN (-1662 2658);
FORCEPROP 2 LAST CDS_LIB standard
J 0
(-1600 2650);
DISPLAY INVISIBLE (-1600 2650);
FORCEPROP 1 LAST BODY_TYPE PLUMBING
J 0
(-1600 2700);
DISPLAY 0.872340 (-1600 2700);
PAINT GREEN (-1600 2700);
DISPLAY INVISIBLE (-1600 2700);
FORCEPROP 1 LAST HDL_TAP TRUE
J 0
(-1275 2525);
DISPLAY 0.872340 (-1275 2525);
DISPLAY INVISIBLE (-1275 2525);
FORCEPROP 1 LAST PATH I89
J 0
(-1602 2650);
DISPLAY 0.872340 (-1602 2650);
PAINT GREEN (-1602 2650);
DISPLAY INVISIBLE (-1602 2650);
FORCEADD OFFPAGE..1
(-4100 1800);
FORCEPROP 2 LAST $XR0 112 
J 0
(-4352 1800);
DISPLAY 0.638298 (-4352 1800);
PAINT MONO (-4352 1800);
FORCEPROP 2 LAST CDS_LIB standard
J 0
(-4100 1800);
PAINT MONO (-4100 1800);
DISPLAY INVISIBLE (-4100 1800);
FORCEPROP 1 LAST OFFPAGE TRUE
J 0
(-3775 1675);
DISPLAY 0.872340 (-3775 1675);
DISPLAY INVISIBLE (-3775 1675);
FORCEPROP 1 LAST COMMENT_BODY TRUE
J 0
(-3975 1700);
DISPLAY 0.872340 (-3975 1700);
PAINT GREEN (-3975 1700);
DISPLAY INVISIBLE (-3975 1700);
FORCEPROP 2 LAST PATH I9
J 0
(-4050 1875);
DISPLAY 1.021277 (-4050 1875);
DISPLAY INVISIBLE (-4050 1875);
FORCEADD TAP..1
(-1600 2800);
FORCEPROP 3 LASTPIN (-1650 2800) SIG_NAME M_H_CPU1_SA_DQ<1>
J 0
(-1640 2810);
DISPLAY 0.659574 (-1640 2810);
PAINT MONO (-1640 2810);
DISPLAY INVISIBLE (-1640 2810);
FORCEPROP 1 LASTPIN (-1650 2800) BN 1
J 0
(-1662 2808);
DISPLAY 0.680851 (-1662 2808);
PAINT GREEN (-1662 2808);
FORCEPROP 2 LAST CDS_LIB standard
J 0
(-1600 2800);
PAINT MONO (-1600 2800);
DISPLAY INVISIBLE (-1600 2800);
FORCEPROP 1 LAST BODY_TYPE PLUMBING
J 0
(-1600 2850);
DISPLAY 0.872340 (-1600 2850);
PAINT GREEN (-1600 2850);
DISPLAY INVISIBLE (-1600 2850);
FORCEPROP 1 LAST HDL_TAP TRUE
J 0
(-1275 2675);
DISPLAY 0.872340 (-1275 2675);
DISPLAY INVISIBLE (-1275 2675);
FORCEPROP 1 LAST PATH I90
J 0
(-1602 2800);
DISPLAY 0.872340 (-1602 2800);
PAINT GREEN (-1602 2800);
DISPLAY INVISIBLE (-1602 2800);
FORCEADD TAP..1
(-1600 2950);
FORCEPROP 3 LASTPIN (-1650 2950) SIG_NAME M_H_CPU1_SA_DQ<4>
J 0
(-1640 2960);
DISPLAY 0.659574 (-1640 2960);
PAINT MONO (-1640 2960);
DISPLAY INVISIBLE (-1640 2960);
FORCEPROP 1 LASTPIN (-1650 2950) BN 4
J 0
(-1662 2958);
DISPLAY 0.680851 (-1662 2958);
PAINT GREEN (-1662 2958);
FORCEPROP 2 LAST CDS_LIB standard
J 0
(-1600 2950);
PAINT MONO (-1600 2950);
DISPLAY INVISIBLE (-1600 2950);
FORCEPROP 1 LAST BODY_TYPE PLUMBING
J 0
(-1600 3000);
DISPLAY 0.872340 (-1600 3000);
PAINT GREEN (-1600 3000);
DISPLAY INVISIBLE (-1600 3000);
FORCEPROP 1 LAST HDL_TAP TRUE
J 0
(-1275 2825);
DISPLAY 0.872340 (-1275 2825);
DISPLAY INVISIBLE (-1275 2825);
FORCEPROP 1 LAST PATH I91
J 0
(-1602 2950);
DISPLAY 0.872340 (-1602 2950);
PAINT GREEN (-1602 2950);
DISPLAY INVISIBLE (-1602 2950);
FORCEADD TAP..1
(-1600 2900);
FORCEPROP 3 LASTPIN (-1650 2900) SIG_NAME M_H_CPU1_SA_DQ<3>
J 0
(-1640 2910);
DISPLAY 0.659574 (-1640 2910);
PAINT MONO (-1640 2910);
DISPLAY INVISIBLE (-1640 2910);
FORCEPROP 1 LASTPIN (-1650 2900) BN 3
J 0
(-1662 2908);
DISPLAY 0.680851 (-1662 2908);
PAINT GREEN (-1662 2908);
FORCEPROP 2 LAST CDS_LIB standard
J 0
(-1600 2900);
PAINT MONO (-1600 2900);
DISPLAY INVISIBLE (-1600 2900);
FORCEPROP 1 LAST BODY_TYPE PLUMBING
J 0
(-1600 2950);
DISPLAY 0.872340 (-1600 2950);
PAINT GREEN (-1600 2950);
DISPLAY INVISIBLE (-1600 2950);
FORCEPROP 1 LAST HDL_TAP TRUE
J 0
(-1275 2775);
DISPLAY 0.872340 (-1275 2775);
DISPLAY INVISIBLE (-1275 2775);
FORCEPROP 1 LAST PATH I92
J 0
(-1602 2900);
DISPLAY 0.872340 (-1602 2900);
PAINT GREEN (-1602 2900);
DISPLAY INVISIBLE (-1602 2900);
FORCEADD TAP..1
(-1600 3000);
FORCEPROP 3 LASTPIN (-1650 3000) SIG_NAME M_H_CPU1_SA_DQ<5>
J 0
(-1640 3010);
DISPLAY 0.659574 (-1640 3010);
PAINT MONO (-1640 3010);
DISPLAY INVISIBLE (-1640 3010);
FORCEPROP 1 LASTPIN (-1650 3000) BN 5
J 0
(-1662 3008);
DISPLAY 0.680851 (-1662 3008);
PAINT GREEN (-1662 3008);
FORCEPROP 2 LAST CDS_LIB standard
J 0
(-1600 3000);
PAINT MONO (-1600 3000);
DISPLAY INVISIBLE (-1600 3000);
FORCEPROP 1 LAST BODY_TYPE PLUMBING
J 0
(-1600 3050);
DISPLAY 0.872340 (-1600 3050);
PAINT GREEN (-1600 3050);
DISPLAY INVISIBLE (-1600 3050);
FORCEPROP 1 LAST HDL_TAP TRUE
J 0
(-1275 2875);
DISPLAY 0.872340 (-1275 2875);
DISPLAY INVISIBLE (-1275 2875);
FORCEPROP 1 LAST PATH I93
J 0
(-1602 3000);
DISPLAY 0.872340 (-1602 3000);
PAINT GREEN (-1602 3000);
DISPLAY INVISIBLE (-1602 3000);
FORCEADD TAP..1
(-1600 3100);
FORCEPROP 3 LASTPIN (-1650 3100) SIG_NAME M_H_CPU1_SA_DQ<7>
J 0
(-1640 3110);
DISPLAY 0.659574 (-1640 3110);
PAINT MONO (-1640 3110);
DISPLAY INVISIBLE (-1640 3110);
FORCEPROP 1 LASTPIN (-1650 3100) BN 7
J 0
(-1662 3108);
DISPLAY 0.680851 (-1662 3108);
PAINT GREEN (-1662 3108);
FORCEPROP 2 LAST CDS_LIB standard
J 0
(-1600 3100);
PAINT MONO (-1600 3100);
DISPLAY INVISIBLE (-1600 3100);
FORCEPROP 1 LAST BODY_TYPE PLUMBING
J 0
(-1600 3150);
DISPLAY 0.872340 (-1600 3150);
PAINT GREEN (-1600 3150);
DISPLAY INVISIBLE (-1600 3150);
FORCEPROP 1 LAST HDL_TAP TRUE
J 0
(-1275 2975);
DISPLAY 0.872340 (-1275 2975);
DISPLAY INVISIBLE (-1275 2975);
FORCEPROP 1 LAST PATH I94
J 0
(-1602 3100);
DISPLAY 0.872340 (-1602 3100);
PAINT GREEN (-1602 3100);
DISPLAY INVISIBLE (-1602 3100);
FORCEADD TAP..1
(-1600 3050);
FORCEPROP 3 LASTPIN (-1650 3050) SIG_NAME M_H_CPU1_SA_DQ<6>
J 0
(-1640 3060);
DISPLAY 0.659574 (-1640 3060);
PAINT MONO (-1640 3060);
DISPLAY INVISIBLE (-1640 3060);
FORCEPROP 1 LASTPIN (-1650 3050) BN 6
J 0
(-1662 3058);
DISPLAY 0.680851 (-1662 3058);
PAINT GREEN (-1662 3058);
FORCEPROP 2 LAST CDS_LIB standard
J 0
(-1600 3050);
PAINT MONO (-1600 3050);
DISPLAY INVISIBLE (-1600 3050);
FORCEPROP 1 LAST BODY_TYPE PLUMBING
J 0
(-1600 3100);
DISPLAY 0.872340 (-1600 3100);
PAINT GREEN (-1600 3100);
DISPLAY INVISIBLE (-1600 3100);
FORCEPROP 1 LAST HDL_TAP TRUE
J 0
(-1275 2925);
DISPLAY 0.872340 (-1275 2925);
DISPLAY INVISIBLE (-1275 2925);
FORCEPROP 1 LAST PATH I95
J 0
(-1602 3050);
DISPLAY 0.872340 (-1602 3050);
PAINT GREEN (-1602 3050);
DISPLAY INVISIBLE (-1602 3050);
FORCEADD TAP..1
(-1600 3200);
FORCEPROP 3 LASTPIN (-1650 3200) SIG_NAME M_H_CPU1_SA_DQ<9>
J 0
(-1640 3210);
DISPLAY 0.659574 (-1640 3210);
PAINT MONO (-1640 3210);
DISPLAY INVISIBLE (-1640 3210);
FORCEPROP 1 LASTPIN (-1650 3200) BN 9
J 0
(-1662 3208);
DISPLAY 0.680851 (-1662 3208);
PAINT GREEN (-1662 3208);
FORCEPROP 2 LAST CDS_LIB standard
J 0
(-1600 3200);
PAINT MONO (-1600 3200);
DISPLAY INVISIBLE (-1600 3200);
FORCEPROP 1 LAST BODY_TYPE PLUMBING
J 0
(-1600 3250);
DISPLAY 0.872340 (-1600 3250);
PAINT GREEN (-1600 3250);
DISPLAY INVISIBLE (-1600 3250);
FORCEPROP 1 LAST HDL_TAP TRUE
J 0
(-1275 3075);
DISPLAY 0.872340 (-1275 3075);
DISPLAY INVISIBLE (-1275 3075);
FORCEPROP 1 LAST PATH I96
J 0
(-1602 3200);
DISPLAY 0.872340 (-1602 3200);
PAINT GREEN (-1602 3200);
DISPLAY INVISIBLE (-1602 3200);
FORCEADD TAP..1
(-1600 3150);
FORCEPROP 3 LASTPIN (-1650 3150) SIG_NAME M_H_CPU1_SA_DQ<8>
J 0
(-1640 3160);
DISPLAY 0.659574 (-1640 3160);
PAINT MONO (-1640 3160);
DISPLAY INVISIBLE (-1640 3160);
FORCEPROP 1 LASTPIN (-1650 3150) BN 8
J 0
(-1662 3158);
DISPLAY 0.680851 (-1662 3158);
PAINT GREEN (-1662 3158);
FORCEPROP 2 LAST CDS_LIB standard
J 0
(-1600 3150);
PAINT MONO (-1600 3150);
DISPLAY INVISIBLE (-1600 3150);
FORCEPROP 1 LAST BODY_TYPE PLUMBING
J 0
(-1600 3200);
DISPLAY 0.872340 (-1600 3200);
PAINT GREEN (-1600 3200);
DISPLAY INVISIBLE (-1600 3200);
FORCEPROP 1 LAST HDL_TAP TRUE
J 0
(-1275 3025);
DISPLAY 0.872340 (-1275 3025);
DISPLAY INVISIBLE (-1275 3025);
FORCEPROP 1 LAST PATH I97
J 0
(-1602 3150);
DISPLAY 0.872340 (-1602 3150);
PAINT GREEN (-1602 3150);
DISPLAY INVISIBLE (-1602 3150);
FORCEADD TAP..1
(-1600 3250);
FORCEPROP 3 LASTPIN (-1650 3250) SIG_NAME M_H_CPU1_SA_DQ<10>
J 0
(-1640 3260);
DISPLAY 0.659574 (-1640 3260);
PAINT MONO (-1640 3260);
DISPLAY INVISIBLE (-1640 3260);
FORCEPROP 1 LASTPIN (-1650 3250) BN 10
J 0
(-1662 3258);
DISPLAY 0.680851 (-1662 3258);
PAINT GREEN (-1662 3258);
FORCEPROP 2 LAST CDS_LIB standard
J 0
(-1600 3250);
PAINT MONO (-1600 3250);
DISPLAY INVISIBLE (-1600 3250);
FORCEPROP 1 LAST BODY_TYPE PLUMBING
J 0
(-1600 3300);
DISPLAY 0.872340 (-1600 3300);
PAINT GREEN (-1600 3300);
DISPLAY INVISIBLE (-1600 3300);
FORCEPROP 1 LAST HDL_TAP TRUE
J 0
(-1275 3125);
DISPLAY 0.872340 (-1275 3125);
DISPLAY INVISIBLE (-1275 3125);
FORCEPROP 1 LAST PATH I98
J 0
(-1602 3250);
DISPLAY 0.872340 (-1602 3250);
PAINT GREEN (-1602 3250);
DISPLAY INVISIBLE (-1602 3250);
FORCEADD TAP..1
(-1600 3300);
FORCEPROP 3 LASTPIN (-1650 3300) SIG_NAME M_H_CPU1_SA_DQ<11>
J 0
(-1640 3310);
DISPLAY 0.659574 (-1640 3310);
PAINT MONO (-1640 3310);
DISPLAY INVISIBLE (-1640 3310);
FORCEPROP 1 LASTPIN (-1650 3300) BN 11
J 0
(-1662 3308);
DISPLAY 0.680851 (-1662 3308);
PAINT GREEN (-1662 3308);
FORCEPROP 2 LAST CDS_LIB standard
J 0
(-1600 3300);
PAINT MONO (-1600 3300);
DISPLAY INVISIBLE (-1600 3300);
FORCEPROP 1 LAST BODY_TYPE PLUMBING
J 0
(-1600 3350);
DISPLAY 0.872340 (-1600 3350);
PAINT GREEN (-1600 3350);
DISPLAY INVISIBLE (-1600 3350);
FORCEPROP 1 LAST HDL_TAP TRUE
J 0
(-1275 3175);
DISPLAY 0.872340 (-1275 3175);
DISPLAY INVISIBLE (-1275 3175);
FORCEPROP 1 LAST PATH I99
J 0
(-1602 3300);
DISPLAY 0.872340 (-1602 3300);
PAINT GREEN (-1602 3300);
DISPLAY INVISIBLE (-1602 3300);
FORCEADD CAD_NOTE..1
(250 -150);
FORCEPROP 0 LAST S1 PLACE THE BYPASS CAPS CLOSE TO DIMM
J 0
(125 -275);
DISPLAY 1.021277 (125 -275);
PAINT WHITE (125 -275);
FORCEPROP 2 LAST CDS_LIB logical_power
J 0
(250 -150);
PAINT MONO (250 -150);
DISPLAY INVISIBLE (250 -150);
FORCEPROP 1 LAST COMMENT_BODY TRUE
J 0
(275 -50);
DISPLAY 0.978723 (275 -50);
DISPLAY INVISIBLE (275 -50);
FORCEADD QUANTA_TITLE_BLOCK_C..1
(4700 -1450);
FORCEPROP 0 LAST CDS_CON_LAST_MODIFIED Fri Aug 25 14:01:33 2023
J 0
(2815 -1435);
PAINT MONO (2815 -1435);
DISPLAY INVISIBLE (2815 -1435);
FORCEPROP 1 LAST CUSTOM_TXT_CDS <CON_LAST_MODIFIED>
J 0
(2815 -1435);
DISPLAY 0.978723 (2815 -1435);
FORCEPROP 2 LAST CUSTOM_TXT_CDS <XR_PAGE_TITLE>
J 0
(-3190 3800);
DISPLAY 0.638298 (-3190 3800);
PAINT PINK (-3190 3800);
DISPLAY INVISIBLE (-3190 3800);
FORCEPROP 2 LAST CUSTOM_TXT_CDS <CON_PAGE_NUM> OF <CON_TOTAL_PAGES>
J 0
(4254 -1432);
DISPLAY 0.978723 (4254 -1432);
FORCEPROP 2 LAST CUSTOM_TXT_CDS <Q_NUMBER>
J 0
(3297 -1347);
DISPLAY 1.212766 (3297 -1347);
FORCEPROP 1 LAST CUSTOM_TXT_CDS <NAME_2>
J 0
(1525 -1400);
FORCEPROP 1 LAST CUSTOM_TXT_CDS <NAME_1>
J 0
(1525 -1275);
FORCEPROP 1 LAST CUSTOM_TXT_CDS <Q_PROJ>
J 0
(2318 -1348);
DISPLAY 1.212766 (2318 -1348);
FORCEPROP 1 LAST CUSTOM_TXT_CDS <Q_REV>
J 0
(4516 -1347);
DISPLAY 1.212766 (4516 -1347);
FORCEPROP 1 LAST Q_TITLE DDR5 - CPU1 CHH DIMM1(YELLOW)
J 0
(-4666 -1424);
DISPLAY 2.446809 (-4666 -1424);
PAINT GREEN (-4666 -1424);
FORCEPROP 1 LAST Q_DEPT 
J 1
(937 -1401);
DISPLAY 1.957447 (937 -1401);
PAINT GREEN (937 -1401);
FORCEPROP 2 LAST CDS_XR_PAGE_TITLE CR-112 : @S9S_MB_2U_LIB.S9S_MB_2U(SCH_1):PAGE112
J 0
(-3190 3800);
DISPLAY 0.638298 (-3190 3800);
PAINT PINK (-3190 3800);
DISPLAY INVISIBLE (-3190 3800);
FORCEPROP 1 LAST COMMENT_BODY TRUE
J 0
(4712 -1463);
DISPLAY 0.978723 (4712 -1463);
PAINT GREEN (4712 -1463);
DISPLAY INVISIBLE (4712 -1463);
FORCEPROP 2 LAST PAGE_BORDER TRUE
J 0
(-3190 3800);
DISPLAY 0.638298 (-3190 3800);
PAINT PINK (-3190 3800);
DISPLAY INVISIBLE (-3190 3800);
FORCEPROP 1 LAST CDS_LMAN_SYM_OUTLINE -9475,6775,100,-125
J 0
(4700 -1450);
DISPLAY 0.468085 (4700 -1450);
PAINT GREEN (4700 -1450);
DISPLAY INVISIBLE (4700 -1450);
FORCEPROP 2 LAST CDS_LIB pure_quanta
J 0
(4700 -1450);
PAINT MONO (4700 -1450);
DISPLAY INVISIBLE (4700 -1450);
WIRE 17 -1 (-1550 4275)(-1550 4325);
WIRE 17 -1 (-1550 4225)(-1550 4275);
WIRE 17 -1 (-1550 4325)(-825 4325);
FORCEPROP 2 LAST SIG_NAME M_H_CPU1_SA_DQ<31:0>
J 0
(-1485 4335);
DISPLAY 0.680851 (-1485 4335);
PAINT WHITE (-1485 4335);
WIRE 17 -1 (-3300 2875)(-3300 2925);
WIRE 17 -1 (-3300 2825)(-3300 2875);
WIRE 17 -1 (-4125 2925)(-3300 2925);
FORCEPROP 2 LAST SIG_NAME M_H_CPU1_SA_CB<7:0>
J 0
(-4035 2935);
DISPLAY 0.680851 (-4035 2935);
PAINT WHITE (-4035 2935);
WIRE 17 -1 (-3300 2775)(-3300 2825);
WIRE 17 -1 (-3300 2725)(-3300 2775);
WIRE 17 -1 (-3300 2675)(-3300 2725);
WIRE 17 -1 (-3300 2625)(-3300 2675);
WIRE 17 -1 (-3300 2575)(-3300 2625);
WIRE 17 -1 (-3300 2425)(-3300 2475);
WIRE 17 -1 (-3300 2375)(-3300 2425);
WIRE 17 -1 (-4125 2475)(-3300 2475);
FORCEPROP 2 LAST SIG_NAME M_H_CPU1_SB_CB<7:0>
J 0
(-4035 2485);
DISPLAY 0.680851 (-4035 2485);
PAINT WHITE (-4035 2485);
WIRE 17 -1 (-3300 3625)(-3300 3675);
WIRE 17 -1 (-3300 3675)(-3300 3725);
WIRE 17 -1 (-3300 3725)(-3300 3775);
WIRE 17 -1 (-3300 3775)(-3300 3825);
WIRE 17 -1 (-3300 3825)(-3300 3875);
WIRE 17 -1 (-3300 3875)(-3300 3925);
WIRE 17 -1 (-4125 3925)(-3300 3925);
FORCEPROP 2 LAST SIG_NAME M_H_CPU1_SB_CA<6:0>
J 0
(-4035 3935);
DISPLAY 0.680851 (-4035 3935);
PAINT WHITE (-4035 3935);
WIRE 17 -1 (-3300 4075)(-3300 4125);
WIRE 17 -1 (-3300 4025)(-3300 4075);
WIRE 17 -1 (-3300 4125)(-3300 4175);
WIRE 17 -1 (-3300 4175)(-3300 4225);
WIRE 17 -1 (-3300 4225)(-3300 4275);
WIRE 17 -1 (-3300 4275)(-3300 4325);
WIRE 17 -1 (-4125 4325)(-3300 4325);
FORCEPROP 2 LAST SIG_NAME M_H_CPU1_SA_CA<6:0>
J 0
(-4035 4335);
DISPLAY 0.680851 (-4035 4335);
PAINT WHITE (-4035 4335);
WIRE 17 -1 (-3300 2325)(-3300 2375);
WIRE 17 -1 (-3300 2275)(-3300 2325);
WIRE 17 -1 (-3300 2225)(-3300 2275);
WIRE 17 -1 (-3300 2175)(-3300 2225);
WIRE 17 -1 (-3300 2125)(-3300 2175);
WIRE 17 -1 (-1550 4175)(-1550 4225);
WIRE 17 -1 (-1550 4125)(-1550 4175);
WIRE 17 -1 (-1550 4075)(-1550 4125);
WIRE 17 -1 (-1550 4025)(-1550 4075);
WIRE 17 -1 (-1550 3975)(-1550 4025);
WIRE 17 -1 (-1550 3925)(-1550 3975);
WIRE 17 -1 (-1550 3875)(-1550 3925);
WIRE 17 -1 (-1550 3825)(-1550 3875);
WIRE 17 -1 (-1550 3775)(-1550 3825);
WIRE 17 -1 (-1550 3725)(-1550 3775);
WIRE 17 -1 (-1550 3675)(-1550 3725);
WIRE 17 -1 (-1550 3625)(-1550 3675);
WIRE 17 -1 (-1550 3575)(-1550 3625);
WIRE 17 -1 (-1550 3525)(-1550 3575);
WIRE 17 -1 (-1550 3475)(-1550 3525);
WIRE 17 -1 (-1550 3425)(-1550 3475);
WIRE 17 -1 (-1550 3375)(-1550 3425);
WIRE 17 -1 (-1550 3325)(-1550 3375);
WIRE 17 -1 (-1550 3275)(-1550 3325);
WIRE 17 -1 (-1550 3225)(-1550 3275);
WIRE 17 -1 (-1550 3175)(-1550 3225);
WIRE 17 -1 (-1550 3125)(-1550 3175);
WIRE 17 -1 (-1550 3075)(-1550 3125);
WIRE 17 -1 (-1550 3025)(-1550 3075);
WIRE 17 -1 (-1550 2975)(-1550 3025);
WIRE 17 -1 (-1550 2925)(-1550 2975);
WIRE 17 -1 (-1550 2875)(-1550 2925);
WIRE 17 -1 (-1550 2825)(-1550 2875);
WIRE 17 -1 (-1550 2775)(-1550 2825);
WIRE 17 -1 (-1550 2625)(-1550 2675);
WIRE 17 -1 (-1550 2575)(-1550 2625);
WIRE 17 -1 (-1550 2675)(-825 2675);
FORCEPROP 2 LAST SIG_NAME M_H_CPU1_SB_DQ<31:0>
J 0
(-1485 2685);
DISPLAY 0.680851 (-1485 2685);
PAINT WHITE (-1485 2685);
WIRE 17 -1 (-1550 2525)(-1550 2575);
WIRE 17 -1 (-1550 2475)(-1550 2525);
WIRE 17 -1 (-1550 2425)(-1550 2475);
WIRE 17 -1 (-1550 2375)(-1550 2425);
WIRE 17 -1 (-1550 2325)(-1550 2375);
WIRE 17 -1 (-1550 2275)(-1550 2325);
WIRE 17 -1 (-1550 2225)(-1550 2275);
WIRE 17 -1 (-1550 2175)(-1550 2225);
WIRE 17 -1 (-1550 2125)(-1550 2175);
WIRE 17 -1 (-1550 2075)(-1550 2125);
WIRE 17 -1 (-1550 2025)(-1550 2075);
WIRE 17 -1 (-1550 1975)(-1550 2025);
WIRE 17 -1 (-1550 1925)(-1550 1975);
WIRE 17 -1 (-1550 1875)(-1550 1925);
WIRE 17 -1 (-1550 1825)(-1550 1875);
WIRE 17 -1 (-1550 1775)(-1550 1825);
WIRE 17 -1 (-1550 1725)(-1550 1775);
WIRE 17 -1 (-1550 1675)(-1550 1725);
WIRE 17 -1 (-1550 1625)(-1550 1675);
WIRE 17 -1 (-1550 1575)(-1550 1625);
WIRE 17 -1 (-1550 1525)(-1550 1575);
WIRE 17 -1 (-1550 1475)(-1550 1525);
WIRE 17 -1 (-1550 1425)(-1550 1475);
WIRE 17 -1 (-1550 1375)(-1550 1425);
WIRE 17 -1 (-1550 1325)(-1550 1375);
WIRE 17 -1 (-1550 1275)(-1550 1325);
WIRE 17 -1 (-1550 1225)(-1550 1275);
WIRE 17 -1 (-1550 1175)(-1550 1225);
WIRE 17 -1 (-1550 1125)(-1550 1175);
WIRE 17 -1 (1200 2375)(1200 2475);
WIRE 17 -1 (1200 2475)(1200 2575);
WIRE 17 -1 (1200 2575)(1200 2675);
WIRE 17 -1 (1200 2775)(1200 2675);
WIRE 17 -1 (1200 2775)(1200 2875);
WIRE 17 -1 (1200 2875)(1200 2975);
WIRE 17 -1 (1200 2975)(1200 3075);
WIRE 17 -1 (1200 3075)(1200 3175);
WIRE 17 -1 (1200 3175)(1200 3275);
WIRE 17 -1 (1200 3275)(2225 3275);
FORCEPROP 2 LAST SIG_NAME M_H_CPU1_SB_DQS_DP<9:0>
J 0
(1440 3285);
DISPLAY 0.680851 (1440 3285);
PAINT WHITE (1440 3285);
WIRE 17 -1 (1200 3425)(1200 3525);
WIRE 17 -1 (1200 3525)(1200 3625);
WIRE 17 -1 (1200 3625)(1200 3725);
WIRE 17 -1 (1200 3825)(1200 3725);
WIRE 17 -1 (1200 3825)(1200 3925);
WIRE 17 -1 (1200 3925)(1200 4025);
WIRE 17 -1 (1200 4025)(1200 4125);
WIRE 17 -1 (1200 4125)(1200 4225);
WIRE 17 -1 (1200 4225)(1200 4325);
WIRE 17 -1 (1200 4325)(2225 4325);
FORCEPROP 2 LAST SIG_NAME M_H_CPU1_SA_DQS_DP<9:0>
J 0
(1440 4335);
DISPLAY 0.680851 (1440 4335);
PAINT WHITE (1440 4335);
WIRE 17 -1 (1375 2325)(1375 2425);
WIRE 17 -1 (1375 2425)(1375 2525);
WIRE 17 -1 (1375 2525)(1375 2625);
WIRE 17 -1 (1375 2725)(1375 2625);
WIRE 17 -1 (1375 2725)(1375 2825);
WIRE 17 -1 (1375 2825)(1375 2925);
WIRE 17 -1 (1375 2925)(1375 3025);
WIRE 17 -1 (1375 3025)(1375 3125);
WIRE 17 -1 (1375 3125)(1375 3225);
WIRE 17 -1 (1375 3225)(2225 3225);
FORCEPROP 2 LAST SIG_NAME M_H_CPU1_SB_DQS_DN<9:0>
J 0
(1440 3235);
DISPLAY 0.680851 (1440 3235);
PAINT WHITE (1440 3235);
WIRE 17 -1 (1375 3375)(1375 3475);
WIRE 17 -1 (1375 3475)(1375 3575);
WIRE 17 -1 (1375 3575)(1375 3675);
WIRE 17 -1 (1375 3775)(1375 3675);
WIRE 17 -1 (1375 3775)(1375 3875);
WIRE 17 -1 (1375 3875)(1375 3975);
WIRE 17 -1 (1375 3975)(1375 4075);
WIRE 17 -1 (1375 4075)(1375 4175);
WIRE 17 -1 (1375 4175)(1375 4275);
WIRE 17 -1 (1375 4275)(2225 4275);
FORCEPROP 2 LAST SIG_NAME M_H_CPU1_SA_DQS_DN<9:0>
J 0
(1440 4285);
DISPLAY 0.680851 (1440 4285);
PAINT WHITE (1440 4285);
WIRE 16 -1 (125 525)(125 700);
WIRE 16 -1 (2825 4800)(2825 4300);
WIRE 16 -1 (-4075 2125)(-4075 1850);
WIRE 16 -1 (1125 700)(1125 650);
WIRE 16 -1 (125 325)(125 100);
WIRE 16 -1 (1750 100)(1750 175);
WIRE 16 -1 (2825 650)(2825 1050);
WIRE 16 -1 (4525 950)(4525 650);
WIRE 16 -1 (4525 1000)(4525 950);
WIRE 16 -1 (4275 950)(4525 950);
WIRE 16 -1 (-3025 -25)(-3025 50);
WIRE 16 -1 (-1825 1200)(-1650 1200);
WIRE 16 -1 (-3025 1450)(-4125 1450);
FORCEPROP 2 LAST SIG_NAME PWRGD_CHH_CPU1_DIMM1
J 0
(-4037 1459);
DISPLAY 0.680851 (-4037 1459);
PAINT WHITE (-4037 1459);
WIRE 16 -1 (-3025 1350)(-4125 1350);
FORCEPROP 2 LAST SIG_NAME TP_CHH_CPU1_DIMM1_FRU_6
J 0
(-4037 1359);
DISPLAY 0.680851 (-4037 1359);
PAINT WHITE (-4037 1359);
WIRE 16 -1 (-3025 1250)(-4125 1250);
FORCEPROP 2 LAST SIG_NAME TP_CHH_CPU1_DIMM1_FRU_4
J 0
(-4037 1259);
DISPLAY 0.680851 (-4037 1259);
PAINT WHITE (-4037 1259);
WIRE 16 -1 (-3025 1200)(-4125 1200);
FORCEPROP 2 LAST SIG_NAME TP_CHH_CPU1_DIMM1_FRU_3
J 0
(-4037 1209);
DISPLAY 0.680851 (-4037 1209);
PAINT WHITE (-4037 1209);
WIRE 16 -1 (-3025 1150)(-4125 1150);
FORCEPROP 2 LAST SIG_NAME TP_CHH_CPU1_DIMM1_FRU_2
J 0
(-4037 1159);
DISPLAY 0.680851 (-4037 1159);
PAINT WHITE (-4037 1159);
WIRE 16 -1 (-3025 1100)(-4125 1100);
FORCEPROP 2 LAST SIG_NAME TP_CHH_CPU1_DIMM1_FRU_1
J 0
(-4037 1109);
DISPLAY 0.680851 (-4037 1109);
PAINT WHITE (-4037 1109);
WIRE 16 -1 (-3025 1050)(-4125 1050);
FORCEPROP 2 LAST SIG_NAME TP_CHH_CPU1_DIMM1_FRU_0
J 0
(-4037 1059);
DISPLAY 0.680851 (-4037 1059);
PAINT WHITE (-4037 1059);
WIRE 16 -1 (-4100 1600)(-2900 1600);
FORCEPROP 2 LAST SIG_NAME I3C_SPD_DDREFGH_CPU1_LVC1_SCL
J 0
(-3960 1610);
DISPLAY 0.680851 (-3960 1610);
PAINT WHITE (-3960 1610);
WIRE 16 -1 (-2900 1600)(-2900 1550);
WIRE 16 -1 (-2900 1550)(-2925 1550);
WIRE 16 -1 (-3025 1700)(-4500 1700);
FORCEPROP 2 LAST SIG_NAME I3C_SPD_DDREFGH_CPU1_LVC1_SCL_R7
J 0
(-4110 1710);
DISPLAY 0.680851 (-4110 1710);
PAINT WHITE (-4110 1710);
WIRE 16 -1 (-4500 1600)(-4500 1700);
WIRE 16 -1 (-4500 1600)(-4300 1600);
WIRE 16 -1 (-3025 1950)(-4125 1950);
FORCEPROP 2 LAST SIG_NAME M_H_CPU1_ALERT_N
J 0
(-4037 1959);
DISPLAY 0.680851 (-4037 1959);
PAINT WHITE (-4037 1959);
WIRE 16 -1 (-3375 2000)(-3025 2000);
WIRE 16 -1 (-3375 2075)(-4125 2075);
FORCEPROP 2 LAST SIG_NAME RST_M_GH_CPU1_FPGA_N
J 0
(-4037 2084);
DISPLAY 0.680851 (-4037 2084);
PAINT WHITE (-4037 2084);
WIRE 16 -1 (-3375 2075)(-3375 2000);
WIRE 16 -1 (-4075 1850)(-3025 1850);
WIRE 16 3135 (2375 925)(-225 925);
WIRE 16 3135 (2375 -375)(2375 925);
WIRE 16 3135 (-225 925)(-225 -375);
WIRE 16 3135 (-225 -375)(2375 -375);
WIRE 16 -1 (-3025 1800)(-4050 1800);
FORCEPROP 2 LAST SIG_NAME PD_CHH_CPU1_DIMM1_SAA
J 0
(-4060 1810);
DISPLAY 0.680851 (-4060 1810);
PAINT WHITE (-4060 1810);
WIRE 16 -1 (-3025 1750)(-4075 1750);
FORCEPROP 2 LAST SIG_NAME I3C_SPD_DDREFGH_CPU1_LVC1_SDA
J 0
(-4085 1760);
DISPLAY 0.680851 (-4085 1760);
PAINT WHITE (-4085 1760);
WIRE 16 -1 (-3200 2150)(-3025 2150);
WIRE 16 -1 (1000 4250)(1275 4250);
WIRE 16 -1 (1000 4150)(1275 4150);
WIRE 16 -1 (1000 4050)(1275 4050);
WIRE 16 -1 (1000 3950)(1275 3950);
WIRE 16 -1 (1000 3850)(1275 3850);
WIRE 16 -1 (1000 3750)(1275 3750);
WIRE 16 -1 (1000 3650)(1275 3650);
WIRE 16 -1 (1000 3550)(1275 3550);
WIRE 16 -1 (1000 3450)(1275 3450);
WIRE 16 -1 (1000 3350)(1275 3350);
WIRE 16 -1 (1000 3200)(1275 3200);
WIRE 16 -1 (1000 3100)(1275 3100);
WIRE 16 -1 (1000 3000)(1275 3000);
WIRE 16 -1 (1000 2900)(1275 2900);
WIRE 16 -1 (1000 2700)(1275 2700);
WIRE 16 -1 (1000 2800)(1275 2800);
WIRE 16 -1 (1000 2600)(1275 2600);
WIRE 16 -1 (1000 2500)(1275 2500);
WIRE 16 -1 (1000 2400)(1275 2400);
WIRE 16 -1 (1000 2300)(1275 2300);
WIRE 16 -1 (1000 4300)(1100 4300);
WIRE 16 -1 (1000 4200)(1100 4200);
WIRE 16 -1 (1000 4100)(1100 4100);
WIRE 16 -1 (1000 4000)(1100 4000);
WIRE 16 -1 (1000 3900)(1100 3900);
WIRE 16 -1 (1000 3800)(1100 3800);
WIRE 16 -1 (1000 3700)(1100 3700);
WIRE 16 -1 (1000 3600)(1100 3600);
WIRE 16 -1 (1000 3500)(1100 3500);
WIRE 16 -1 (1000 3400)(1100 3400);
WIRE 16 -1 (1000 3250)(1100 3250);
WIRE 16 -1 (1000 3150)(1100 3150);
WIRE 16 -1 (1000 3050)(1100 3050);
WIRE 16 -1 (1000 2950)(1100 2950);
WIRE 16 -1 (1000 2850)(1100 2850);
WIRE 16 -1 (1000 2750)(1100 2750);
WIRE 16 -1 (1000 2650)(1100 2650);
WIRE 16 -1 (1000 2550)(1100 2550);
WIRE 16 -1 (1000 2450)(1100 2450);
WIRE 16 -1 (1000 2350)(1100 2350);
WIRE 16 -1 (-3200 2550)(-3025 2550);
WIRE 16 -1 (4275 4300)(4525 4300);
WIRE 16 -1 (4275 4250)(4525 4250);
WIRE 16 -1 (4525 4300)(4525 4250);
WIRE 16 -1 (4275 4200)(4525 4200);
WIRE 16 -1 (4525 4250)(4525 4200);
WIRE 16 -1 (4275 4150)(4525 4150);
WIRE 16 -1 (4525 4200)(4525 4150);
WIRE 16 -1 (4275 4100)(4525 4100);
WIRE 16 -1 (4525 4150)(4525 4100);
WIRE 16 -1 (4275 4050)(4525 4050);
WIRE 16 -1 (4525 4100)(4525 4050);
WIRE 16 -1 (4275 4000)(4525 4000);
WIRE 16 -1 (4525 4050)(4525 4000);
WIRE 16 -1 (4275 3950)(4525 3950);
WIRE 16 -1 (4525 4000)(4525 3950);
WIRE 16 -1 (4275 3900)(4525 3900);
WIRE 16 -1 (4525 3950)(4525 3900);
WIRE 16 -1 (4275 3850)(4525 3850);
WIRE 16 -1 (4525 3900)(4525 3850);
WIRE 16 -1 (4275 3800)(4525 3800);
WIRE 16 -1 (4525 3850)(4525 3800);
WIRE 16 -1 (4275 3750)(4525 3750);
WIRE 16 -1 (4525 3800)(4525 3750);
WIRE 16 -1 (4275 3700)(4525 3700);
WIRE 16 -1 (4525 3750)(4525 3700);
WIRE 16 -1 (4275 3650)(4525 3650);
WIRE 16 -1 (4525 3700)(4525 3650);
WIRE 16 -1 (4275 3600)(4525 3600);
WIRE 16 -1 (4525 3650)(4525 3600);
WIRE 16 -1 (4275 3550)(4525 3550);
WIRE 16 -1 (4525 3550)(4525 3600);
WIRE 16 -1 (4275 3500)(4525 3500);
WIRE 16 -1 (4525 3550)(4525 3500);
WIRE 16 -1 (4525 3450)(4275 3450);
WIRE 16 -1 (4525 3500)(4525 3450);
WIRE 16 -1 (4525 3400)(4275 3400);
WIRE 16 -1 (4525 3450)(4525 3400);
WIRE 16 -1 (4275 3350)(4525 3350);
WIRE 16 -1 (4525 3400)(4525 3350);
WIRE 16 -1 (4275 3300)(4525 3300);
WIRE 16 -1 (4525 3350)(4525 3300);
WIRE 16 -1 (4275 3250)(4525 3250);
WIRE 16 -1 (4525 3300)(4525 3250);
WIRE 16 -1 (4275 3200)(4525 3200);
WIRE 16 -1 (4525 3250)(4525 3200);
WIRE 16 -1 (4275 3150)(4525 3150);
WIRE 16 -1 (4525 3200)(4525 3150);
WIRE 16 -1 (4275 3100)(4525 3100);
WIRE 16 -1 (4525 3150)(4525 3100);
WIRE 16 -1 (4275 3050)(4525 3050);
WIRE 16 -1 (4525 3050)(4525 3100);
WIRE 16 -1 (4275 3000)(4525 3000);
WIRE 16 -1 (4525 3050)(4525 3000);
WIRE 16 -1 (4525 2950)(4275 2950);
WIRE 16 -1 (4525 3000)(4525 2950);
WIRE 16 -1 (4525 2900)(4275 2900);
WIRE 16 -1 (4525 2950)(4525 2900);
WIRE 16 -1 (4275 2850)(4525 2850);
WIRE 16 -1 (4525 2900)(4525 2850);
WIRE 16 -1 (4275 2800)(4525 2800);
WIRE 16 -1 (4525 2850)(4525 2800);
WIRE 16 -1 (4275 2750)(4525 2750);
WIRE 16 -1 (4525 2800)(4525 2750);
WIRE 16 -1 (4275 2700)(4525 2700);
WIRE 16 -1 (4525 2750)(4525 2700);
WIRE 16 -1 (4275 2650)(4525 2650);
WIRE 16 -1 (4525 2700)(4525 2650);
WIRE 16 -1 (4275 2600)(4525 2600);
WIRE 16 -1 (4525 2650)(4525 2600);
WIRE 16 -1 (4275 2550)(4525 2550);
WIRE 16 -1 (4525 2550)(4525 2600);
WIRE 16 -1 (4275 2500)(4525 2500);
WIRE 16 -1 (4525 2550)(4525 2500);
WIRE 16 -1 (4525 2450)(4275 2450);
WIRE 16 -1 (4525 2500)(4525 2450);
WIRE 16 -1 (4525 2400)(4275 2400);
WIRE 16 -1 (4525 2450)(4525 2400);
WIRE 16 -1 (4275 2350)(4525 2350);
WIRE 16 -1 (4525 2400)(4525 2350);
WIRE 16 -1 (4275 2300)(4525 2300);
WIRE 16 -1 (4525 2350)(4525 2300);
WIRE 16 -1 (4275 2250)(4525 2250);
WIRE 16 -1 (4525 2300)(4525 2250);
WIRE 16 -1 (4275 2200)(4525 2200);
WIRE 16 -1 (4525 2250)(4525 2200);
WIRE 16 -1 (4275 2150)(4525 2150);
WIRE 16 -1 (4525 2200)(4525 2150);
WIRE 16 -1 (4275 2100)(4525 2100);
WIRE 16 -1 (4525 2150)(4525 2100);
WIRE 16 -1 (4275 2050)(4525 2050);
WIRE 16 -1 (4525 2050)(4525 2100);
WIRE 16 -1 (4275 2000)(4525 2000);
WIRE 16 -1 (4525 2050)(4525 2000);
WIRE 16 -1 (4525 1950)(4275 1950);
WIRE 16 -1 (4525 2000)(4525 1950);
WIRE 16 -1 (4525 1900)(4275 1900);
WIRE 16 -1 (4525 1950)(4525 1900);
WIRE 16 -1 (4525 1850)(4275 1850);
WIRE 16 -1 (4525 1900)(4525 1850);
WIRE 16 -1 (4525 1800)(4275 1800);
WIRE 16 -1 (4525 1850)(4525 1800);
WIRE 16 -1 (4275 1750)(4525 1750);
WIRE 16 -1 (4525 1750)(4525 1800);
WIRE 16 -1 (4525 1700)(4275 1700);
WIRE 16 -1 (4525 1700)(4525 1750);
WIRE 16 -1 (4525 1650)(4275 1650);
WIRE 16 -1 (4525 1700)(4525 1650);
WIRE 16 -1 (4525 1600)(4275 1600);
WIRE 16 -1 (4525 1650)(4525 1600);
WIRE 16 -1 (4275 1550)(4525 1550);
WIRE 16 -1 (4525 1600)(4525 1550);
WIRE 16 -1 (4275 1500)(4525 1500);
WIRE 16 -1 (4525 1550)(4525 1500);
WIRE 16 -1 (4275 1450)(4525 1450);
WIRE 16 -1 (4525 1500)(4525 1450);
WIRE 16 -1 (4275 1400)(4525 1400);
WIRE 16 -1 (4525 1450)(4525 1400);
WIRE 16 -1 (4275 1350)(4525 1350);
WIRE 16 -1 (4525 1400)(4525 1350);
WIRE 16 -1 (4275 1300)(4525 1300);
WIRE 16 -1 (4525 1350)(4525 1300);
WIRE 16 -1 (4275 1250)(4525 1250);
WIRE 16 -1 (4525 1300)(4525 1250);
WIRE 16 -1 (4275 1200)(4525 1200);
WIRE 16 -1 (4525 1200)(4525 1250);
WIRE 16 -1 (4275 1150)(4525 1150);
WIRE 16 -1 (4525 1200)(4525 1150);
WIRE 16 -1 (4275 1050)(4525 1050);
WIRE 16 -1 (4525 1150)(4525 1050);
WIRE 16 -1 (4525 1050)(4525 1000);
WIRE 16 -1 (4275 1000)(4525 1000);
WIRE 16 -1 (3075 4300)(2825 4300);
WIRE 16 -1 (2825 4300)(2825 4250);
WIRE 16 -1 (2825 4250)(3075 4250);
WIRE 16 -1 (2825 4250)(2825 4200);
WIRE 16 -1 (3075 4200)(2825 4200);
WIRE 16 -1 (-3200 4000)(-3025 4000);
WIRE 16 -1 (-3200 3800)(-3025 3800);
WIRE 16 -1 (-3025 3200)(-4125 3200);
FORCEPROP 2 LAST SIG_NAME M_H_CPU1_SB_CS_N<1>
J 0
(-4037 3209);
DISPLAY 0.680851 (-4037 3209);
PAINT WHITE (-4037 3209);
WIRE 16 -1 (-3025 3150)(-4125 3150);
FORCEPROP 2 LAST SIG_NAME M_H_CPU1_SB_CS_N<0>
J 0
(-4037 3159);
DISPLAY 0.680851 (-4037 3159);
PAINT WHITE (-4037 3159);
WIRE 16 -1 (-1825 2250)(-1650 2250);
WIRE 16 -1 (-1825 2200)(-1650 2200);
WIRE 16 -1 (-1825 2150)(-1650 2150);
WIRE 16 -1 (3075 4150)(2825 4150);
WIRE 16 -1 (2825 4100)(2825 4150);
WIRE 16 -1 (2825 4100)(3075 4100);
WIRE 16 -1 (3075 4050)(2825 4050);
WIRE 16 -1 (2825 4050)(2825 4100);
WIRE 16 -1 (2825 4000)(2825 4050);
WIRE 16 -1 (2825 4000)(3075 4000);
WIRE 16 -1 (2825 3950)(2825 4000);
WIRE 16 -1 (2825 3950)(3075 3950);
WIRE 16 -1 (2825 3900)(2825 3950);
WIRE 16 -1 (2825 3900)(3075 3900);
WIRE 16 -1 (2825 3850)(2825 3900);
WIRE 16 -1 (2825 3850)(3075 3850);
WIRE 16 -1 (2825 3800)(2825 3850);
WIRE 16 -1 (2825 3800)(3075 3800);
WIRE 16 -1 (2825 3750)(2825 3800);
WIRE 16 -1 (2825 3750)(3075 3750);
WIRE 16 -1 (2825 3700)(2825 3750);
WIRE 16 -1 (2825 3700)(3075 3700);
WIRE 16 -1 (2825 3650)(2825 3700);
WIRE 16 -1 (2825 3650)(3075 3650);
WIRE 16 -1 (2825 3600)(2825 3650);
WIRE 16 -1 (2825 3600)(3075 3600);
WIRE 16 -1 (2825 3550)(2825 3600);
WIRE 16 -1 (3075 3550)(2825 3550);
WIRE 16 -1 (2825 3500)(2825 3550);
WIRE 16 -1 (2825 3500)(3075 3500);
WIRE 16 -1 (2825 3450)(2825 3500);
WIRE 16 -1 (2825 3450)(3075 3450);
WIRE 16 -1 (2825 3400)(2825 3450);
WIRE 16 -1 (2825 3400)(3075 3400);
WIRE 16 -1 (2825 3350)(2825 3400);
WIRE 16 -1 (2825 3350)(3075 3350);
WIRE 16 -1 (2825 3300)(2825 3350);
WIRE 16 -1 (2825 3300)(3075 3300);
WIRE 16 -1 (2825 3250)(2825 3300);
WIRE 16 -1 (2825 3250)(3075 3250);
WIRE 16 -1 (2825 3200)(2825 3250);
WIRE 16 -1 (2825 3200)(3075 3200);
WIRE 16 -1 (2825 3150)(2825 3200);
WIRE 16 -1 (2825 3150)(3075 3150);
WIRE 16 -1 (2825 3100)(2825 3150);
WIRE 16 -1 (2825 3100)(3075 3100);
WIRE 16 -1 (2825 3050)(2825 3100);
WIRE 16 -1 (3075 3050)(2825 3050);
WIRE 16 -1 (2825 3000)(2825 3050);
WIRE 16 -1 (2825 3000)(3075 3000);
WIRE 16 -1 (2825 2950)(2825 3000);
WIRE 16 -1 (2825 2950)(3075 2950);
WIRE 16 -1 (2825 2900)(2825 2950);
WIRE 16 -1 (2825 2900)(3075 2900);
WIRE 16 -1 (2825 2850)(2825 2900);
WIRE 16 -1 (2825 2850)(3075 2850);
WIRE 16 -1 (2825 2800)(2825 2850);
WIRE 16 -1 (2825 2800)(3075 2800);
WIRE 16 -1 (2825 2750)(2825 2800);
WIRE 16 -1 (2825 2750)(3075 2750);
WIRE 16 -1 (2825 2700)(2825 2750);
WIRE 16 -1 (2825 2700)(3075 2700);
WIRE 16 -1 (2825 2650)(2825 2700);
WIRE 16 -1 (2825 2650)(3075 2650);
WIRE 16 -1 (2825 2600)(2825 2650);
WIRE 16 -1 (2825 2600)(3075 2600);
WIRE 16 -1 (2825 2550)(2825 2600);
WIRE 16 -1 (3075 2550)(2825 2550);
WIRE 16 -1 (2825 2500)(2825 2550);
WIRE 16 -1 (2825 2500)(3075 2500);
WIRE 16 -1 (2825 2450)(2825 2500);
WIRE 16 -1 (2825 2450)(3075 2450);
WIRE 16 -1 (2825 2400)(2825 2450);
WIRE 16 -1 (2825 2400)(3075 2400);
WIRE 16 -1 (2825 2350)(2825 2400);
WIRE 16 -1 (2825 2350)(3075 2350);
WIRE 16 -1 (2825 2300)(2825 2350);
WIRE 16 -1 (2825 2300)(3075 2300);
WIRE 16 -1 (2825 2250)(2825 2300);
WIRE 16 -1 (2825 2250)(3075 2250);
WIRE 16 -1 (2825 2200)(2825 2250);
WIRE 16 -1 (2825 2200)(3075 2200);
WIRE 16 -1 (2825 2150)(2825 2200);
WIRE 16 -1 (2825 2150)(3075 2150);
WIRE 16 -1 (2825 2100)(2825 2150);
WIRE 16 -1 (2825 2100)(3075 2100);
WIRE 16 -1 (2825 2050)(2825 2100);
WIRE 16 -1 (3075 2050)(2825 2050);
WIRE 16 -1 (2825 2000)(3075 2000);
WIRE 16 -1 (2825 2000)(2825 2050);
WIRE 16 -1 (2825 1950)(2825 2000);
WIRE 16 -1 (2825 1950)(3075 1950);
WIRE 16 -1 (2825 1900)(2825 1950);
WIRE 16 -1 (2825 1900)(3075 1900);
WIRE 16 -1 (2825 1850)(2825 1900);
WIRE 16 -1 (2825 1850)(3075 1850);
WIRE 16 -1 (2825 1800)(2825 1850);
WIRE 16 -1 (2825 1800)(3075 1800);
WIRE 16 -1 (2825 1750)(2825 1800);
WIRE 16 -1 (2825 1750)(3075 1750);
WIRE 16 -1 (2825 1700)(2825 1750);
WIRE 16 -1 (2825 1700)(3075 1700);
WIRE 16 -1 (2825 1650)(2825 1700);
WIRE 16 -1 (2825 1650)(3075 1650);
WIRE 16 -1 (2825 1600)(2825 1650);
WIRE 16 -1 (2825 1600)(3075 1600);
WIRE 16 -1 (2825 1550)(2825 1600);
WIRE 16 -1 (3075 1550)(2825 1550);
WIRE 16 -1 (2825 1500)(2825 1550);
WIRE 16 -1 (2825 1500)(3075 1500);
WIRE 16 -1 (2825 1450)(2825 1500);
WIRE 16 -1 (2825 1450)(3075 1450);
WIRE 16 -1 (2825 1400)(2825 1450);
WIRE 16 -1 (2825 1400)(3075 1400);
WIRE 16 -1 (2825 1350)(2825 1400);
WIRE 16 -1 (2825 1350)(3075 1350);
WIRE 16 -1 (2825 1300)(2825 1350);
WIRE 16 -1 (2825 1300)(3075 1300);
WIRE 16 -1 (2825 1250)(2825 1300);
WIRE 16 -1 (2825 1250)(3075 1250);
WIRE 16 -1 (2825 1200)(2825 1250);
WIRE 16 -1 (2825 1200)(3075 1200);
WIRE 16 -1 (2825 1150)(2825 1200);
WIRE 16 -1 (2825 1150)(3075 1150);
WIRE 16 -1 (2825 1100)(2825 1150);
WIRE 16 -1 (2825 1100)(3075 1100);
WIRE 16 -1 (2825 1050)(2825 1100);
WIRE 16 -1 (2825 1050)(3075 1050);
WIRE 16 -1 (-3200 2300)(-3025 2300);
WIRE 16 -1 (-1825 2450)(-1650 2450);
WIRE 16 -1 (-1825 1750)(-1650 1750);
WIRE 16 -1 (-3025 1300)(-4125 1300);
FORCEPROP 2 LAST SIG_NAME TP_CHH_CPU1_DIMM1_FRU_5
J 0
(-4037 1309);
DISPLAY 0.680851 (-4037 1309);
PAINT WHITE (-4037 1309);
WIRE 16 -1 (-3025 3450)(-4125 3450);
FORCEPROP 2 LAST SIG_NAME M_H_CPU1_SB_PAR
J 0
(-4037 3459);
DISPLAY 0.680851 (-4037 3459);
PAINT WHITE (-4037 3459);
WIRE 16 -1 (-3025 3500)(-4125 3500);
FORCEPROP 2 LAST SIG_NAME M_H_CPU1_SA_PAR
J 0
(-4037 3509);
DISPLAY 0.680851 (-4037 3509);
PAINT WHITE (-4037 3509);
WIRE 16 -1 (-3025 850)(-4125 850);
FORCEPROP 2 LAST SIG_NAME M_H_CPU1_SB_RSP<0>
J 0
(-4037 859);
DISPLAY 0.680851 (-4037 859);
PAINT WHITE (-4037 859);
WIRE 16 -1 (-3025 900)(-4125 900);
FORCEPROP 2 LAST SIG_NAME M_H_CPU1_SA_RSP<0>
J 0
(-4037 909);
DISPLAY 0.680851 (-4037 909);
PAINT WHITE (-4037 909);
WIRE 16 -1 (-1825 1100)(-1650 1100);
WIRE 16 -1 (-1825 1150)(-1650 1150);
WIRE 16 -1 (-1825 1250)(-1650 1250);
WIRE 16 -1 (-1825 1300)(-1650 1300);
WIRE 16 -1 (-1825 1350)(-1650 1350);
WIRE 16 -1 (-1825 1400)(-1650 1400);
WIRE 16 -1 (-1825 1450)(-1650 1450);
WIRE 16 -1 (-1825 1500)(-1650 1500);
WIRE 16 -1 (-1825 1550)(-1650 1550);
WIRE 16 -1 (-1825 1600)(-1650 1600);
WIRE 16 -1 (-1825 1650)(-1650 1650);
WIRE 16 -1 (-1825 1700)(-1650 1700);
WIRE 16 -1 (-1825 1800)(-1650 1800);
WIRE 16 -1 (-1825 1850)(-1650 1850);
WIRE 16 -1 (-1825 1900)(-1650 1900);
WIRE 16 -1 (-1825 1950)(-1650 1950);
WIRE 16 -1 (-1825 2000)(-1650 2000);
WIRE 16 -1 (-1825 2050)(-1650 2050);
WIRE 16 -1 (-1825 2100)(-1650 2100);
WIRE 16 -1 (-1825 2300)(-1650 2300);
WIRE 16 -1 (-1825 2350)(-1650 2350);
WIRE 16 -1 (-1825 2400)(-1650 2400);
WIRE 16 -1 (-1825 2500)(-1650 2500);
WIRE 16 -1 (-1825 2550)(-1650 2550);
WIRE 16 -1 (-1825 2600)(-1650 2600);
WIRE 16 -1 (-1825 2650)(-1650 2650);
WIRE 16 -1 (-1825 2750)(-1650 2750);
WIRE 16 -1 (-1825 2800)(-1650 2800);
WIRE 16 -1 (-1825 2850)(-1650 2850);
WIRE 16 -1 (-1825 2900)(-1650 2900);
WIRE 16 -1 (-1825 2950)(-1650 2950);
WIRE 16 -1 (-1825 3000)(-1650 3000);
WIRE 16 -1 (-1825 3050)(-1650 3050);
WIRE 16 -1 (-1825 3100)(-1650 3100);
WIRE 16 -1 (-1825 3150)(-1650 3150);
WIRE 16 -1 (-1825 3200)(-1650 3200);
WIRE 16 -1 (-1825 3250)(-1650 3250);
WIRE 16 -1 (-1825 3300)(-1650 3300);
WIRE 16 -1 (-1825 3350)(-1650 3350);
WIRE 16 -1 (-1825 3400)(-1650 3400);
WIRE 16 -1 (-1825 3450)(-1650 3450);
WIRE 16 -1 (-1825 3500)(-1650 3500);
WIRE 16 -1 (-1825 3550)(-1650 3550);
WIRE 16 -1 (-1825 3600)(-1650 3600);
WIRE 16 -1 (-1825 3650)(-1650 3650);
WIRE 16 -1 (-1825 3700)(-1650 3700);
WIRE 16 -1 (-1825 3750)(-1650 3750);
WIRE 16 -1 (-1825 3800)(-1650 3800);
WIRE 16 -1 (-1825 3850)(-1650 3850);
WIRE 16 -1 (-1825 3900)(-1650 3900);
WIRE 16 -1 (-1825 3950)(-1650 3950);
WIRE 16 -1 (-1825 4000)(-1650 4000);
WIRE 16 -1 (-1825 4050)(-1650 4050);
WIRE 16 -1 (-1825 4100)(-1650 4100);
WIRE 16 -1 (-1825 4150)(-1650 4150);
WIRE 16 -1 (-1825 4200)(-1650 4200);
WIRE 16 -1 (-1825 4250)(-1650 4250);
WIRE 16 -1 (-3025 3350)(-4125 3350);
FORCEPROP 2 LAST SIG_NAME M_H_CPU1_SA_CS_N<1>
J 0
(-4037 3359);
DISPLAY 0.680851 (-4037 3359);
PAINT WHITE (-4037 3359);
WIRE 16 -1 (-3025 3300)(-4125 3300);
FORCEPROP 2 LAST SIG_NAME M_H_CPU1_SA_CS_N<0>
J 0
(-4037 3309);
DISPLAY 0.680851 (-4037 3309);
PAINT WHITE (-4037 3309);
WIRE 16 -1 (-3025 3050)(-4125 3050);
FORCEPROP 2 LAST SIG_NAME M_H_CPU1_CLK_DP<0>
J 0
(-4037 3059);
DISPLAY 0.680851 (-4037 3059);
PAINT WHITE (-4037 3059);
WIRE 16 -1 (-3025 3000)(-4125 3000);
FORCEPROP 2 LAST SIG_NAME M_H_CPU1_CLK_DN<0>
J 0
(-4037 3009);
DISPLAY 0.680851 (-4037 3009);
PAINT WHITE (-4037 3009);
WIRE 16 -1 (-3200 2100)(-3025 2100);
WIRE 16 -1 (-3200 2200)(-3025 2200);
WIRE 16 -1 (-3200 2250)(-3025 2250);
WIRE 16 -1 (-3200 2350)(-3025 2350);
WIRE 16 -1 (-3200 2400)(-3025 2400);
WIRE 16 -1 (-3200 2650)(-3025 2650);
WIRE 16 -1 (-3200 2700)(-3025 2700);
WIRE 16 -1 (-3200 2800)(-3025 2800);
WIRE 16 -1 (-3200 2850)(-3025 2850);
WIRE 16 -1 (-3200 3900)(-3025 3900);
WIRE 16 -1 (-3200 4300)(-3025 4300);
WIRE 16 -1 (-3200 3850)(-3025 3850);
WIRE 16 -1 (-3200 4250)(-3025 4250);
WIRE 16 -1 (-3200 4200)(-3025 4200);
WIRE 16 -1 (-3200 3750)(-3025 3750);
WIRE 16 -1 (-3200 4150)(-3025 4150);
WIRE 16 -1 (-3200 3700)(-3025 3700);
WIRE 16 -1 (-3200 4100)(-3025 4100);
WIRE 16 -1 (-3200 3650)(-3025 3650);
WIRE 16 -1 (-3200 4050)(-3025 4050);
WIRE 16 -1 (-3200 3600)(-3025 3600);
WIRE 16 -1 (-3200 2450)(-3025 2450);
WIRE 16 -1 (-3200 2600)(-3025 2600);
WIRE 16 -1 (-3200 2750)(-3025 2750);
WIRE 16 -1 (-3200 2900)(-3025 2900);
WIRE 16 -1 (-1825 4300)(-1650 4300);
WIRE 16 -1 (-3025 350)(-4125 350);
FORCEPROP 2 LAST SIG_NAME PD_CHH_CPU1_DIMM1_SAA
J 0
(-4037 359);
DISPLAY 0.680851 (-4037 359);
PAINT WHITE (-4037 359);
WIRE 16 -1 (-3025 250)(-3025 350);
WIRE 16 -1 (1125 650)(1125 525);
WIRE 16 -1 (1750 650)(1125 650);
WIRE 16 -1 (1750 525)(1750 650);
WIRE 16 -1 (1125 175)(1125 325);
WIRE 16 -1 (1750 175)(1125 175);
WIRE 16 -1 (1750 175)(1750 325);
DOT 1 (4525 950);
DOT 1 (4525 1000);
DOT 1 (4525 1050);
DOT 1 (1125 650);
DOT 1 (1750 175);
DOT 1 (2825 1100);
DOT 1 (2825 1050);
DOT 1 (2825 1150);
DOT 1 (2825 1200);
DOT 1 (2825 1250);
DOT 1 (2825 1300);
DOT 1 (2825 1350);
DOT 1 (2825 1400);
DOT 1 (2825 1450);
DOT 1 (2825 1500);
DOT 1 (2825 1600);
DOT 1 (2825 1550);
DOT 1 (2825 1650);
DOT 1 (2825 1750);
DOT 1 (2825 1800);
DOT 1 (2825 1850);
DOT 1 (2825 1900);
DOT 1 (2825 1950);
DOT 1 (2825 2000);
DOT 1 (2825 2050);
DOT 1 (2825 2150);
DOT 1 (2825 2100);
DOT 1 (2825 2200);
DOT 1 (2825 2250);
DOT 1 (2825 2300);
DOT 1 (2825 2350);
DOT 1 (2825 2400);
DOT 1 (2825 2550);
DOT 1 (2825 2650);
DOT 1 (2825 2600);
DOT 1 (2825 2700);
DOT 1 (2825 2750);
DOT 1 (2825 2850);
DOT 1 (2825 3000);
DOT 1 (2825 2950);
DOT 1 (2825 3050);
DOT 1 (2825 3150);
DOT 1 (2825 3100);
DOT 1 (2825 3200);
DOT 1 (2825 3300);
DOT 1 (2825 3350);
DOT 1 (2825 3400);
DOT 1 (2825 3450);
DOT 1 (2825 3500);
DOT 1 (2825 3550);
DOT 1 (2825 3650);
DOT 1 (2825 3600);
DOT 1 (2825 3700);
DOT 1 (2825 3750);
DOT 1 (2825 3800);
DOT 1 (2825 3850);
DOT 1 (2825 3900);
DOT 1 (2825 4000);
DOT 1 (2825 3950);
DOT 1 (2825 4050);
DOT 1 (2825 4100);
DOT 1 (2825 4300);
DOT 1 (2825 4250);
DOT 1 (4525 1150);
DOT 1 (4525 1200);
DOT 1 (4525 1250);
DOT 1 (4525 1300);
DOT 1 (4525 1350);
DOT 1 (4525 1400);
DOT 1 (4525 1450);
DOT 1 (4525 1500);
DOT 1 (4525 1600);
DOT 1 (4525 1550);
DOT 1 (4525 1650);
DOT 1 (4525 1700);
DOT 1 (4525 1750);
DOT 1 (4525 1800);
DOT 1 (4525 1850);
DOT 1 (4525 1900);
DOT 1 (4525 1950);
DOT 1 (4525 2000);
DOT 1 (4525 2050);
DOT 1 (4525 2100);
DOT 1 (4525 2150);
DOT 1 (4525 2200);
DOT 1 (4525 2250);
DOT 1 (4525 2300);
DOT 1 (4525 2350);
DOT 1 (4525 2400);
DOT 1 (4525 2450);
DOT 1 (4525 2500);
DOT 1 (4525 2550);
DOT 1 (4525 2650);
DOT 1 (4525 2600);
DOT 1 (4525 2700);
DOT 1 (4525 2750);
DOT 1 (4525 2800);
DOT 1 (4525 2850);
DOT 1 (4525 2900);
DOT 1 (4525 2950);
DOT 1 (4525 3000);
DOT 1 (4525 3050);
DOT 1 (4525 3100);
DOT 1 (4525 3150);
DOT 1 (4525 3200);
DOT 1 (4525 3250);
DOT 1 (4525 3300);
DOT 1 (4525 3350);
DOT 1 (4525 3400);
DOT 1 (4525 3500);
DOT 1 (4525 3550);
DOT 1 (4525 3750);
DOT 1 (4525 3800);
DOT 1 (4525 3850);
DOT 1 (4525 3900);
DOT 1 (4525 3950);
DOT 1 (4525 4000);
DOT 1 (4525 4050);
DOT 1 (4525 4100);
DOT 1 (4525 4150);
DOT 1 (4525 4200);
DOT 1 (4525 4250);
DOT 1 (2825 2800);
DOT 1 (2825 2900);
DOT 1 (2825 3250);
DOT 1 (2825 2450);
DOT 1 (2825 2500);
DOT 1 (2825 1700);
DOT 1 (4525 3700);
DOT 1 (4525 3600);
DOT 1 (4525 3650);
DOT 1 (4525 3450);
FORCENOTE
20210728 MODIFY FOR GT
(-4525 4975) 0;
DISPLAY LEFT (-4525 4975);
DISPLAY 2.510638 (-4525 4975);
PAINT PINK (-4525 4975);
QUIT
